G04 ================== begin FILE IDENTIFICATION RECORD ==================*
G04 Layout Name:  12523-1.brd*
G04 Film Name:    12523-1_X_Y*
G04 File Format:  Gerber RS274X*
G04 File Origin:  Cadence Allegro 16.2-s031*
G04 Origin Date:  Fri Oct 19 14:59:05 2012*
G04 *
G04 Layer:  BOARD GEOMETRY/PANEL_DRAWING*
G04 *
G04 Offset:    (0.00 0.00)*
G04 Mirror:    No*
G04 Mode:      Positive*
G04 Rotation:  0*
G04 FullContactRelief:  No*
G04 UndefLineWidth:     6.00*
G04 ================== end FILE IDENTIFICATION RECORD ====================*
%FSLAX35Y35*MOIN*%
%IR0*IPPOS*OFA0.00000B0.00000*MIA0B0*SFA1.00000B1.00000*%
%ADD10C,.006*%
G75*
%LPD*%
G75*
G36*
G01X173041Y-482460D02*
X174232Y-492815D01*
X176967Y-482756D01*
X173041Y-482460D01*
G37*
G36*
G01X184333Y-524533D02*
X178323Y-516016D01*
X180745Y-526155D01*
X184333Y-524533D01*
G37*
G54D10*
G01X2870454Y-796310D02*
X-254151D01*
G01D02*
Y1400383D01*
G01X2851517Y-777373D02*
X-235214D01*
G01D02*
Y1381446D01*
G01X-246520Y-671993D02*
X-245545Y-673553D01*
X-244375Y-674593D01*
X-243010Y-675113D01*
X-241450Y-674593D01*
X-240280Y-673553D01*
X-239110Y-671993D01*
X-238720Y-669913D01*
Y-659513D01*
G01X-254151Y-561491D02*
X-235214D01*
G01X-244960Y-443630D02*
X-240280D01*
G01X-242620D02*
Y-459230D01*
G01X-244960D02*
X-240280D01*
G01X-254151Y-345608D02*
X-235214D01*
G01X-254151D02*
X-235214D01*
G01X-246715Y-243539D02*
Y-227939D01*
G01X-238525D02*
Y-243539D01*
G01Y-235739D02*
X-246715D01*
G01X-254151Y-129727D02*
X-235214D01*
G01X-254151D02*
X-235214D01*
G01X-241450Y-19856D02*
X-237550D01*
Y-24536D01*
X-238720Y-26096D01*
X-240085Y-27136D01*
X-242035Y-27656D01*
X-243985Y-27136D01*
X-245350Y-26096D01*
X-246520Y-24536D01*
X-247300Y-22716D01*
X-247690Y-20636D01*
Y-18816D01*
X-247300Y-17256D01*
X-246520Y-15436D01*
X-245350Y-13876D01*
X-244180Y-12836D01*
X-242620Y-12056D01*
X-241255D01*
X-239695Y-12576D01*
X-238525Y-13616D01*
G01X-254151Y86155D02*
X-235214D01*
G01X-254151D02*
X-235214D01*
G01X-246704Y188415D02*
Y204015D01*
X-239294D01*
G01X-242024Y196475D02*
X-246704D01*
G01X-254151Y302037D02*
X-235214D01*
G01X-254151D02*
X-235214D01*
G01X-254151D02*
X-235214D01*
G01X-238720Y404486D02*
X-246520D01*
Y420086D01*
X-238720D01*
G01X-241840Y412546D02*
X-246520D01*
G01X-254151Y517918D02*
X-235214D01*
G01X-254151D02*
X-235214D01*
G01X-246910Y620179D02*
Y635779D01*
X-243010D01*
X-241450Y634999D01*
X-240280Y633959D01*
X-239305Y632399D01*
X-238525Y630579D01*
X-238330Y627979D01*
X-238525Y625379D01*
X-239305Y623559D01*
X-240280Y621999D01*
X-241450Y620959D01*
X-243010Y620179D01*
X-246910D01*
G01X-254151Y733800D02*
X-235214D01*
G01X-254151D02*
X-235214D01*
G01X-238330Y850550D02*
X-239500Y851330D01*
X-240865Y851850D01*
X-242425D01*
X-244180Y851070D01*
X-245545Y849770D01*
X-246520Y848210D01*
X-247300Y845610D01*
X-247495Y843270D01*
X-247105Y840930D01*
X-246520Y839370D01*
X-245350Y837810D01*
X-243985Y836770D01*
X-242620Y836250D01*
X-241255D01*
X-239890Y836770D01*
X-238720Y837550D01*
X-237745Y838590D01*
G01X-254151Y949683D02*
X-235214D01*
G01X-254151D02*
X-235214D01*
G01X-241060Y1060262D02*
X-240280Y1061042D01*
X-239695Y1062342D01*
X-239305Y1064162D01*
X-239695Y1065722D01*
X-240475Y1066762D01*
X-241840Y1067542D01*
X-247105D01*
Y1051942D01*
X-240670D01*
X-239305Y1052982D01*
X-238525Y1054542D01*
X-238135Y1056362D01*
X-238525Y1058182D01*
X-239695Y1059742D01*
X-241060Y1060262D01*
X-247105D01*
G01X-254151Y1165564D02*
X-235214D01*
G01X-247495Y1267824D02*
X-242620Y1283424D01*
X-237745Y1267824D01*
G01X-239500Y1273284D02*
X-245740D01*
G01X-254151Y1400383D02*
X2870454D01*
G01X-235214Y1381446D02*
X2851517D01*
G01X-115742Y-792523D02*
Y-776923D01*
X-118082Y-780043D01*
G01Y-792523D02*
X-113402D01*
G01X-115059Y-11024D02*
X-115925Y-11313D01*
X-116575Y-12034D01*
X-117008Y-12900D01*
X-117333Y-14055D01*
X-117441Y-15355D01*
X-117333Y-16654D01*
X-117008Y-17809D01*
X-116575Y-18675D01*
X-115925Y-19396D01*
X-115059Y-19685D01*
X-114193Y-19396D01*
X-113543Y-18675D01*
X-113110Y-17809D01*
X-112785Y-16654D01*
X-112677Y-15355D01*
X-112785Y-14055D01*
X-113110Y-12900D01*
X-113543Y-12034D01*
X-114193Y-11313D01*
X-115059Y-11024D01*
G01X-106398Y-19974D02*
X-106615Y-19829D01*
Y-19541D01*
X-106398Y-19396D01*
X-106181Y-19541D01*
Y-19829D01*
X-106398Y-19974D01*
G01X-97737Y-11024D02*
X-98603Y-11313D01*
X-99253Y-12034D01*
X-99686Y-12900D01*
X-100011Y-14055D01*
X-100119Y-15355D01*
X-100011Y-16654D01*
X-99686Y-17809D01*
X-99253Y-18675D01*
X-98603Y-19396D01*
X-97737Y-19685D01*
X-96871Y-19396D01*
X-96221Y-18675D01*
X-95788Y-17809D01*
X-95463Y-16654D01*
X-95355Y-15355D01*
X-95463Y-14055D01*
X-95788Y-12900D01*
X-96221Y-12034D01*
X-96871Y-11313D01*
X-97737Y-11024D01*
G01X-89076D02*
X-89942Y-11313D01*
X-90592Y-12034D01*
X-91025Y-12900D01*
X-91350Y-14055D01*
X-91458Y-15355D01*
X-91350Y-16654D01*
X-91025Y-17809D01*
X-90592Y-18675D01*
X-89942Y-19396D01*
X-89076Y-19685D01*
X-88210Y-19396D01*
X-87560Y-18675D01*
X-87127Y-17809D01*
X-86802Y-16654D01*
X-86694Y-15355D01*
X-86802Y-14055D01*
X-87127Y-12900D01*
X-87560Y-12034D01*
X-88210Y-11313D01*
X-89076Y-11024D01*
G01X-117441Y1614D02*
X-116791Y892D01*
X-116033Y459D01*
X-115059Y315D01*
X-114085Y604D01*
X-113327Y1181D01*
X-112785Y2191D01*
X-112677Y3346D01*
X-112894Y4501D01*
X-113435Y5223D01*
X-114193Y5800D01*
X-114951Y5945D01*
X-115709Y5800D01*
X-116683Y5223D01*
X-116358Y8976D01*
X-113435D01*
G01X-106398Y26D02*
X-106615Y171D01*
Y459D01*
X-106398Y604D01*
X-106181Y459D01*
Y171D01*
X-106398Y26D01*
G01X-97737Y8976D02*
X-98603Y8687D01*
X-99253Y7966D01*
X-99686Y7100D01*
X-100011Y5945D01*
X-100119Y4645D01*
X-100011Y3346D01*
X-99686Y2191D01*
X-99253Y1325D01*
X-98603Y604D01*
X-97737Y315D01*
X-96871Y604D01*
X-96221Y1325D01*
X-95788Y2191D01*
X-95463Y3346D01*
X-95355Y4645D01*
X-95463Y5945D01*
X-95788Y7100D01*
X-96221Y7966D01*
X-96871Y8687D01*
X-97737Y8976D01*
G01X-89076D02*
X-89942Y8687D01*
X-90592Y7966D01*
X-91025Y7100D01*
X-91350Y5945D01*
X-91458Y4645D01*
X-91350Y3346D01*
X-91025Y2191D01*
X-90592Y1325D01*
X-89942Y604D01*
X-89076Y315D01*
X-88210Y604D01*
X-87560Y1325D01*
X-87127Y2191D01*
X-86802Y3346D01*
X-86694Y4645D01*
X-86802Y5945D01*
X-87127Y7100D01*
X-87560Y7966D01*
X-88210Y8687D01*
X-89076Y8976D01*
G01X-133059Y468315D02*
Y476976D01*
X-134358Y475244D01*
G01Y468315D02*
X-131760D01*
G01X-126455Y475533D02*
X-125805Y476398D01*
X-125048Y476832D01*
X-124181Y476976D01*
X-123099Y476687D01*
X-122341Y475966D01*
X-122124Y475100D01*
X-122233Y474233D01*
X-122666Y473512D01*
X-124831Y472068D01*
X-125805Y471058D01*
X-126455Y469614D01*
X-126672Y468315D01*
X-122124D01*
G01X-118119Y469614D02*
X-117469Y468892D01*
X-116711Y468459D01*
X-115737Y468315D01*
X-114763Y468604D01*
X-114005Y469181D01*
X-113463Y470191D01*
X-113355Y471346D01*
X-113572Y472501D01*
X-114113Y473223D01*
X-114871Y473800D01*
X-115629Y473945D01*
X-116387Y473800D01*
X-117361Y473223D01*
X-117036Y476976D01*
X-114113D01*
G01X-107076Y468026D02*
X-107293Y468171D01*
Y468459D01*
X-107076Y468604D01*
X-106859Y468459D01*
Y468171D01*
X-107076Y468026D01*
G01X-98415Y476976D02*
X-99281Y476687D01*
X-99931Y475966D01*
X-100364Y475100D01*
X-100689Y473945D01*
X-100797Y472645D01*
X-100689Y471346D01*
X-100364Y470191D01*
X-99931Y469325D01*
X-99281Y468604D01*
X-98415Y468315D01*
X-97549Y468604D01*
X-96899Y469325D01*
X-96466Y470191D01*
X-96141Y471346D01*
X-96033Y472645D01*
X-96141Y473945D01*
X-96466Y475100D01*
X-96899Y475966D01*
X-97549Y476687D01*
X-98415Y476976D01*
G01X-89754D02*
X-90620Y476687D01*
X-91270Y475966D01*
X-91703Y475100D01*
X-92028Y473945D01*
X-92136Y472645D01*
X-92028Y471346D01*
X-91703Y470191D01*
X-91270Y469325D01*
X-90620Y468604D01*
X-89754Y468315D01*
X-88888Y468604D01*
X-88238Y469325D01*
X-87805Y470191D01*
X-87480Y471346D01*
X-87372Y472645D01*
X-87480Y473945D01*
X-87805Y475100D01*
X-88238Y475966D01*
X-88888Y476687D01*
X-89754Y476976D01*
G01X-133059Y478315D02*
Y486976D01*
X-134358Y485244D01*
G01Y478315D02*
X-131760D01*
G01X-126455Y485533D02*
X-125805Y486398D01*
X-125048Y486832D01*
X-124181Y486976D01*
X-123099Y486687D01*
X-122341Y485966D01*
X-122124Y485100D01*
X-122233Y484233D01*
X-122666Y483512D01*
X-124831Y482068D01*
X-125805Y481058D01*
X-126455Y479614D01*
X-126672Y478315D01*
X-122124D01*
G01X-115954D02*
X-115737Y480191D01*
X-115412Y481779D01*
X-114979Y483223D01*
X-114438Y484811D01*
X-113572Y486976D01*
X-117902D01*
G01X-107076Y478026D02*
X-107293Y478171D01*
Y478459D01*
X-107076Y478604D01*
X-106859Y478459D01*
Y478171D01*
X-107076Y478026D01*
G01X-98415Y486976D02*
X-99281Y486687D01*
X-99931Y485966D01*
X-100364Y485100D01*
X-100689Y483945D01*
X-100797Y482645D01*
X-100689Y481346D01*
X-100364Y480191D01*
X-99931Y479325D01*
X-99281Y478604D01*
X-98415Y478315D01*
X-97549Y478604D01*
X-96899Y479325D01*
X-96466Y480191D01*
X-96141Y481346D01*
X-96033Y482645D01*
X-96141Y483945D01*
X-96466Y485100D01*
X-96899Y485966D01*
X-97549Y486687D01*
X-98415Y486976D01*
G01X-89754D02*
X-90620Y486687D01*
X-91270Y485966D01*
X-91703Y485100D01*
X-92028Y483945D01*
X-92136Y482645D01*
X-92028Y481346D01*
X-91703Y480191D01*
X-91270Y479325D01*
X-90620Y478604D01*
X-89754Y478315D01*
X-88888Y478604D01*
X-88238Y479325D01*
X-87805Y480191D01*
X-87480Y481346D01*
X-87372Y482645D01*
X-87480Y483945D01*
X-87805Y485100D01*
X-88238Y485966D01*
X-88888Y486687D01*
X-89754Y486976D01*
G01X-135116Y957533D02*
X-134466Y958398D01*
X-133709Y958832D01*
X-132842Y958976D01*
X-131760Y958687D01*
X-131002Y957966D01*
X-130785Y957100D01*
X-130894Y956233D01*
X-131327Y955512D01*
X-133492Y954068D01*
X-134466Y953058D01*
X-135116Y951614D01*
X-135333Y950315D01*
X-130785D01*
G01X-123099D02*
Y958976D01*
X-127105Y952769D01*
X-121691D01*
G01X-115954Y950315D02*
X-115737Y952191D01*
X-115412Y953779D01*
X-114979Y955223D01*
X-114438Y956811D01*
X-113572Y958976D01*
X-117902D01*
G01X-107076Y950026D02*
X-107293Y950171D01*
Y950459D01*
X-107076Y950604D01*
X-106859Y950459D01*
Y950171D01*
X-107076Y950026D01*
G01X-98415Y958976D02*
X-99281Y958687D01*
X-99931Y957966D01*
X-100364Y957100D01*
X-100689Y955945D01*
X-100797Y954645D01*
X-100689Y953346D01*
X-100364Y952191D01*
X-99931Y951325D01*
X-99281Y950604D01*
X-98415Y950315D01*
X-97549Y950604D01*
X-96899Y951325D01*
X-96466Y952191D01*
X-96141Y953346D01*
X-96033Y954645D01*
X-96141Y955945D01*
X-96466Y957100D01*
X-96899Y957966D01*
X-97549Y958687D01*
X-98415Y958976D01*
G01X-89754D02*
X-90620Y958687D01*
X-91270Y957966D01*
X-91703Y957100D01*
X-92028Y955945D01*
X-92136Y954645D01*
X-92028Y953346D01*
X-91703Y952191D01*
X-91270Y951325D01*
X-90620Y950604D01*
X-89754Y950315D01*
X-88888Y950604D01*
X-88238Y951325D01*
X-87805Y952191D01*
X-87480Y953346D01*
X-87372Y954645D01*
X-87480Y955945D01*
X-87805Y957100D01*
X-88238Y957966D01*
X-88888Y958687D01*
X-89754Y958976D01*
G01X-135116Y977533D02*
X-134466Y978398D01*
X-133709Y978832D01*
X-132842Y978976D01*
X-131760Y978687D01*
X-131002Y977966D01*
X-130785Y977100D01*
X-130894Y976233D01*
X-131327Y975512D01*
X-133492Y974068D01*
X-134466Y973058D01*
X-135116Y971614D01*
X-135333Y970315D01*
X-130785D01*
G01X-126780Y971614D02*
X-126130Y970892D01*
X-125372Y970459D01*
X-124398Y970315D01*
X-123424Y970604D01*
X-122666Y971181D01*
X-122124Y972191D01*
X-122016Y973346D01*
X-122233Y974501D01*
X-122774Y975223D01*
X-123532Y975800D01*
X-124290Y975945D01*
X-125048Y975800D01*
X-126022Y975223D01*
X-125697Y978976D01*
X-122774D01*
G01X-117794Y977533D02*
X-117144Y978398D01*
X-116387Y978832D01*
X-115520Y978976D01*
X-114438Y978687D01*
X-113680Y977966D01*
X-113463Y977100D01*
X-113572Y976233D01*
X-114005Y975512D01*
X-116170Y974068D01*
X-117144Y973058D01*
X-117794Y971614D01*
X-118011Y970315D01*
X-113463D01*
G01X-107076Y970026D02*
X-107293Y970171D01*
Y970459D01*
X-107076Y970604D01*
X-106859Y970459D01*
Y970171D01*
X-107076Y970026D01*
G01X-98415Y978976D02*
X-99281Y978687D01*
X-99931Y977966D01*
X-100364Y977100D01*
X-100689Y975945D01*
X-100797Y974645D01*
X-100689Y973346D01*
X-100364Y972191D01*
X-99931Y971325D01*
X-99281Y970604D01*
X-98415Y970315D01*
X-97549Y970604D01*
X-96899Y971325D01*
X-96466Y972191D01*
X-96141Y973346D01*
X-96033Y974645D01*
X-96141Y975945D01*
X-96466Y977100D01*
X-96899Y977966D01*
X-97549Y978687D01*
X-98415Y978976D01*
G01X-89754D02*
X-90620Y978687D01*
X-91270Y977966D01*
X-91703Y977100D01*
X-92028Y975945D01*
X-92136Y974645D01*
X-92028Y973346D01*
X-91703Y972191D01*
X-91270Y971325D01*
X-90620Y970604D01*
X-89754Y970315D01*
X-88888Y970604D01*
X-88238Y971325D01*
X-87805Y972191D01*
X-87480Y973346D01*
X-87372Y974645D01*
X-87480Y975945D01*
X-87805Y977100D01*
X-88238Y977966D01*
X-88888Y978687D01*
X-89754Y978976D01*
G01X-115742Y1385233D02*
Y1400833D01*
X-118082Y1397713D01*
G01Y1385233D02*
X-113402D01*
G01X-83307Y-19685D02*
X-43307D01*
G01X0Y0D02*
X-83307D01*
G01Y472441D02*
X-7874D01*
G01X0Y480315D02*
X-83307D01*
G01Y952756D02*
X-43307D01*
G01X-43308Y972441D02*
X-83308D01*
G01X-9864Y-777373D02*
Y-796310D01*
G01X85820Y-19685D02*
X-29308D01*
G01X-43308Y-5685D02*
G03X-29308Y-19685I14000J0D01*
G01X0Y3937D02*
Y106969D01*
G01Y3937D02*
Y106969D01*
G01X636457Y0D02*
X3937D01*
G01X636457D02*
X3937D01*
G01X30157Y43307D02*
X0D01*
G01Y3937D02*
G03X3937Y0I3937J0D01*
G01X0Y3937D02*
G03X3937Y0I3937J0D01*
G01X-43308Y-5685D02*
Y103032D01*
G01X-19331Y15748D02*
G03X-27913I-4291J0D01*
G01D02*
G03X-19331I4291J0D01*
G01X-7874Y50259D02*
Y3937D01*
G01D02*
G03X3937Y-7874I11811J0D01*
G01D02*
X77283D01*
G01X30157Y78740D02*
X0D01*
G01X-7874Y103032D02*
Y75456D01*
G01Y75460D02*
G03X0I3937J0D01*
G01X-15622Y54794D02*
Y70794D01*
G01X-26122Y62794D02*
X-21122D01*
G01X-23622Y65294D02*
Y60294D01*
G01X-21122Y65294D02*
Y60294D01*
G01X-26122D02*
Y65294D01*
G01X-21122D02*
X-26122D01*
G01Y60294D02*
X-21122D01*
G01X-31622Y70794D02*
X-15622D01*
G01X-31622D02*
Y54794D01*
G01D02*
X-15622D01*
G01X0Y50259D02*
G03X-7874I-3937J0D01*
G01X-43307Y286142D02*
Y116811D01*
G01X-41339Y288110D02*
Y114843D01*
G01Y288110D02*
Y114843D01*
G01X-37402Y192047D02*
Y154803D01*
G01Y152047D02*
Y114803D01*
G01X-12598D02*
Y152047D01*
G01Y154803D02*
Y192047D01*
G01X-43307Y116811D02*
X-37402Y110906D01*
G01X-41339Y114843D02*
X-37402Y110906D01*
G01D02*
X-3937D01*
G01X-37402D02*
X-3937D01*
G01X-37402Y114803D02*
X-12598D01*
G01Y152047D02*
X-37402D01*
G01Y154803D02*
X-12598D01*
G01X0Y106969D02*
G03X-3937Y110906I-3937J0D01*
G01X0Y106969D02*
G03X-3937Y110906I-3937J0D01*
G01X-43308Y103032D02*
X-7874D01*
G01X-37402Y232047D02*
Y194803D01*
G01X-12598D02*
Y232047D01*
G01Y192047D02*
X-37402D01*
G01Y194803D02*
X-12598D01*
G01X-37402Y272047D02*
Y234803D01*
G01X-12598D02*
Y272047D01*
G01Y232047D02*
X-37402D01*
G01Y234803D02*
X-12598D01*
G01Y272047D02*
X-37402D01*
G01X-43307Y360039D02*
Y300709D01*
G01X-41339Y362008D02*
Y298740D01*
G01Y362008D02*
Y298740D01*
G01X-37402Y333780D02*
Y330630D01*
G01Y328780D02*
Y325630D01*
G01Y323780D02*
Y320630D01*
G01Y318780D02*
Y315630D01*
G01Y313780D02*
Y310630D01*
G01Y308780D02*
Y305630D01*
G01Y303780D02*
Y300630D01*
G01Y292047D02*
Y274803D01*
G01X-17717Y300630D02*
Y303780D01*
G01Y305630D02*
Y308780D01*
G01Y310630D02*
Y313780D01*
G01Y315630D02*
Y318780D01*
G01Y320630D02*
Y323780D01*
G01Y325630D02*
Y328780D01*
G01Y330630D02*
Y333780D01*
G01X-12598Y274803D02*
Y292047D01*
G01X-37402D02*
X-41339Y288110D01*
G01X-37402Y292047D02*
X-43307Y286142D01*
G01Y300709D02*
X-37402Y294803D01*
G01X-41339Y298740D02*
X-37402Y294803D01*
G01Y274803D02*
X-12598D01*
G01Y292047D02*
X-37402D01*
G01D02*
X-1378D01*
G01X-12598D02*
X-1378D01*
G01X-37402Y294803D02*
X-1378D01*
G01X-37402D02*
X-1378D01*
G01X-37402Y300630D02*
X-17717D01*
G01Y303780D02*
X-37402D01*
G01Y305630D02*
X-17717D01*
G01Y308780D02*
X-37402D01*
G01Y310630D02*
X-17717D01*
G01Y313780D02*
X-37402D01*
G01Y315630D02*
X-17717D01*
G01Y318780D02*
X-37402D01*
G01Y320630D02*
X-17717D01*
G01Y323780D02*
X-37402D01*
G01Y325630D02*
X-17717D01*
G01Y328780D02*
X-37402D01*
G01Y330630D02*
X-17717D01*
G01X-1378Y292047D02*
G03Y294803I0J1378D01*
G01Y292047D02*
G03Y294803I0J1378D01*
G01X-37402Y358780D02*
Y355630D01*
G01Y353780D02*
Y350630D01*
G01Y348780D02*
Y345630D01*
G01Y343780D02*
Y340630D01*
G01Y338780D02*
Y335630D01*
G01Y365945D02*
X-41339Y362008D01*
G01X-37402Y365945D02*
X-43307Y360039D01*
G01X-17717Y335630D02*
Y338780D01*
G01Y340630D02*
Y343780D01*
G01Y345630D02*
Y348780D01*
G01Y350630D02*
Y353780D01*
G01Y355630D02*
Y358780D01*
G01X0Y369882D02*
Y468504D01*
G01Y369882D02*
Y468504D01*
G01X-17717Y333780D02*
X-37402D01*
G01Y335630D02*
X-17717D01*
G01Y338780D02*
X-37402D01*
G01Y340630D02*
X-17717D01*
G01Y343780D02*
X-37402D01*
G01Y345630D02*
X-17717D01*
G01Y348780D02*
X-37402D01*
G01Y350630D02*
X-17717D01*
G01Y353780D02*
X-37402D01*
G01Y355630D02*
X-17717D01*
G01Y358780D02*
X-37402D01*
G01X-3937Y365945D02*
X-37402D01*
G01X-3937D02*
X-37402D01*
G01X-3937D02*
G03X0Y369882I0J3937D01*
G01X-3937Y365945D02*
G03X0Y369882I0J3937D01*
G01X-7874Y401397D02*
Y373819D01*
G01D02*
X-43307D01*
G01D02*
X-43308Y373820D01*
G01D02*
Y583347D01*
G01X30157Y397638D02*
X0D01*
G01X30157Y433071D02*
X0D01*
G01Y401397D02*
G03X-7874I-3937J0D01*
G01Y426594D02*
G03X0I3937J0D01*
G01X-7874D02*
Y530574D01*
G01X3937Y472441D02*
X636457D01*
G01X3937D02*
X636457D01*
G01X3937D02*
G03X0Y468504I0J-3937D01*
G01X3937Y472441D02*
G03X0Y468504I0J-3937D01*
G01Y484252D02*
Y587283D01*
G01Y484252D02*
Y587283D01*
G01X636457Y480315D02*
X3937D01*
G01X636457D02*
X3937D01*
G01X0Y484252D02*
G03X3937Y480315I3937J0D01*
G01X0Y484252D02*
G03X3937Y480315I3937J0D01*
G01X-7874Y472441D02*
X0D01*
G01X30157Y523622D02*
X0D01*
G01X30157Y559055D02*
X0D01*
G01X-7874Y583347D02*
Y555771D01*
G01D02*
G03X0I3937J0D01*
G01Y530574D02*
G03X-7874I-3937J0D01*
G01X-43307Y766457D02*
Y597126D01*
G01X-41339Y768425D02*
Y595157D01*
G01Y768425D02*
Y595157D01*
G01X-37402Y632362D02*
Y595118D01*
G01X-12598D02*
Y632362D01*
G01X-43307Y597126D02*
X-37402Y591220D01*
G01X-41339Y595157D02*
X-37402Y591220D01*
G01D02*
X-3937D01*
G01X-37402D02*
X-3937D01*
G01X-37402Y595118D02*
X-12598D01*
G01X0Y587283D02*
G03X-3937Y591220I-3937J0D01*
G01X0Y587283D02*
G03X-3937Y591220I-3937J0D01*
G01X-43308Y583347D02*
X-7874D01*
G01X-37402Y672362D02*
Y635118D01*
G01X-12598D02*
Y672362D01*
G01Y632362D02*
X-37402D01*
G01Y635118D02*
X-12598D01*
G01Y672362D02*
X-37402D01*
G01Y752362D02*
Y715118D01*
G01Y712362D02*
Y675118D01*
G01X-12598D02*
Y712362D01*
G01Y715118D02*
Y752362D01*
G01X-37402Y675118D02*
X-12598D01*
G01Y712362D02*
X-37402D01*
G01Y715118D02*
X-12598D01*
G01X-43307Y840354D02*
Y781024D01*
G01X-41339Y842323D02*
Y779055D01*
G01Y842323D02*
Y779055D01*
G01X-37402Y789094D02*
Y785945D01*
G01Y784094D02*
Y780945D01*
G01Y772362D02*
Y755118D01*
G01X-17717Y780945D02*
Y784094D01*
G01Y785945D02*
Y789094D01*
G01X-12598Y755118D02*
Y772362D01*
G01X-37402D02*
X-41339Y768425D01*
G01X-37402Y772362D02*
X-43307Y766457D01*
G01Y781024D02*
X-37402Y775118D01*
G01X-41339Y779055D02*
X-37402Y775118D01*
G01X-12598Y752362D02*
X-37402D01*
G01Y755118D02*
X-12598D01*
G01Y772362D02*
X-37402D01*
G01D02*
X-1378D01*
G01X-12598D02*
X-1378D01*
G01X-37402Y775118D02*
X-1378D01*
G01X-37402D02*
X-1378D01*
G01X-37402Y780945D02*
X-17717D01*
G01Y784094D02*
X-37402D01*
G01Y785945D02*
X-17717D01*
G01X-1378Y772362D02*
G03Y775118I0J1378D01*
G01Y772362D02*
G03Y775118I0J1378D01*
G01X-37402Y839094D02*
Y835945D01*
G01Y834094D02*
Y830945D01*
G01Y829094D02*
Y825945D01*
G01Y824094D02*
Y820945D01*
G01Y819094D02*
Y815945D01*
G01Y814094D02*
Y810945D01*
G01Y809094D02*
Y805945D01*
G01Y804094D02*
Y800945D01*
G01Y799094D02*
Y795945D01*
G01Y794094D02*
Y790945D01*
G01Y846260D02*
X-41339Y842323D01*
G01X-37402Y846260D02*
X-43307Y840354D01*
G01X-17717Y790945D02*
Y794094D01*
G01Y795945D02*
Y799094D01*
G01Y800945D02*
Y804094D01*
G01Y805945D02*
Y809094D01*
G01Y810945D02*
Y814094D01*
G01Y815945D02*
Y819094D01*
G01Y820945D02*
Y824094D01*
G01Y825945D02*
Y829094D01*
G01Y830945D02*
Y834094D01*
G01Y835945D02*
Y839094D01*
G01Y789094D02*
X-37402D01*
G01Y790945D02*
X-17717D01*
G01Y794094D02*
X-37402D01*
G01Y795945D02*
X-17717D01*
G01Y799094D02*
X-37402D01*
G01Y800945D02*
X-17717D01*
G01Y804094D02*
X-37402D01*
G01Y805945D02*
X-17717D01*
G01Y809094D02*
X-37402D01*
G01Y810945D02*
X-17717D01*
G01Y814094D02*
X-37402D01*
G01Y815945D02*
X-17717D01*
G01Y819094D02*
X-37402D01*
G01Y820945D02*
X-17717D01*
G01Y824094D02*
X-37402D01*
G01Y825945D02*
X-17717D01*
G01Y829094D02*
X-37402D01*
G01Y830945D02*
X-17717D01*
G01Y834094D02*
X-37402D01*
G01Y835945D02*
X-17717D01*
G01Y839094D02*
X-37402D01*
G01X0Y850197D02*
Y948819D01*
G01Y850197D02*
Y948819D01*
G01X-3937Y846260D02*
X-37402D01*
G01X-3937D02*
X-37402D01*
G01X30157Y877953D02*
X0D01*
G01X-3937Y846260D02*
G03X0Y850197I0J3937D01*
G01X-3937Y846260D02*
G03X0Y850197I0J3937D01*
G01X-7874Y881712D02*
Y854134D01*
G01D02*
X-43308D01*
G01D02*
Y958441D01*
G01X0Y881711D02*
G03X-7874I-3937J0D01*
G01X30157Y913386D02*
X0D01*
G01X3937Y952756D02*
X636457D01*
G01X3937D02*
X636457D01*
G01X3937D02*
G03X0Y948819I0J-3937D01*
G01X3937Y952756D02*
G03X0Y948819I0J-3937D01*
G01X-29308Y972441D02*
G03X-43308Y958441I0J-14000D01*
G01X-19331Y937008D02*
G03X-27913I-4291J0D01*
G01D02*
G03X-19331I4291J0D01*
G01X-26122Y916269D02*
X-21122D01*
G01X-26122Y913769D02*
Y918769D01*
G01X-21122D02*
X-26122D01*
G01Y913769D02*
X-21122D01*
G01X-31622Y924269D02*
X-15622D01*
G01X-31622D02*
Y908269D01*
G01D02*
X-15622D01*
G01X-23622Y918769D02*
Y913769D01*
G01X-21122Y918769D02*
Y913769D01*
G01X0Y952756D02*
X-43307D01*
G01X-7874Y906909D02*
G03X0I3937J0D01*
G01X-7874D02*
Y948819D01*
G01X3937Y960630D02*
G03X-7874Y948819I0J-11811D01*
G01X-15622Y924269D02*
Y908269D01*
G01X-29308Y972441D02*
X1317968D01*
G01X-43308Y1000315D02*
Y972441D01*
G01X3937Y960630D02*
X77283D01*
G01X-49968Y1005563D02*
X-49679Y1004697D01*
X-48958Y1004047D01*
X-48092Y1003614D01*
X-46937Y1003289D01*
X-45637Y1003181D01*
X-44338Y1003289D01*
X-43183Y1003614D01*
X-42317Y1004047D01*
X-41596Y1004697D01*
X-41307Y1005563D01*
X-41596Y1006429D01*
X-42317Y1007079D01*
X-43183Y1007512D01*
X-44338Y1007837D01*
X-45637Y1007945D01*
X-46937Y1007837D01*
X-48092Y1007512D01*
X-48958Y1007079D01*
X-49679Y1006429D01*
X-49968Y1005563D01*
G01X-41018Y1014224D02*
X-41163Y1014007D01*
X-41451D01*
X-41596Y1014224D01*
X-41451Y1014441D01*
X-41163D01*
X-41018Y1014224D01*
G01X-49968Y1022885D02*
X-49679Y1022019D01*
X-48958Y1021369D01*
X-48092Y1020936D01*
X-46937Y1020611D01*
X-45637Y1020503D01*
X-44338Y1020611D01*
X-43183Y1020936D01*
X-42317Y1021369D01*
X-41596Y1022019D01*
X-41307Y1022885D01*
X-41596Y1023751D01*
X-42317Y1024401D01*
X-43183Y1024834D01*
X-44338Y1025159D01*
X-45637Y1025267D01*
X-46937Y1025159D01*
X-48092Y1024834D01*
X-48958Y1024401D01*
X-49679Y1023751D01*
X-49968Y1022885D01*
G01Y1031546D02*
X-49679Y1030680D01*
X-48958Y1030030D01*
X-48092Y1029597D01*
X-46937Y1029272D01*
X-45637Y1029164D01*
X-44338Y1029272D01*
X-43183Y1029597D01*
X-42317Y1030030D01*
X-41596Y1030680D01*
X-41307Y1031546D01*
X-41596Y1032412D01*
X-42317Y1033062D01*
X-43183Y1033495D01*
X-44338Y1033820D01*
X-45637Y1033928D01*
X-46937Y1033820D01*
X-48092Y1033495D01*
X-48958Y1033062D01*
X-49679Y1032412D01*
X-49968Y1031546D01*
G01X-9864Y1400383D02*
Y1381446D01*
G01X30157Y43307D02*
G03Y78740I0J17716D01*
G01X37146Y61024D02*
G03I-6989J0D01*
G01X17244Y226378D02*
Y246063D01*
G01X29055D02*
Y226378D01*
G01X25118Y222441D02*
X21181D01*
G01Y250000D02*
X25118D01*
G01X17244Y226378D02*
G03X21181Y222441I3937J0D01*
G01X25118D02*
G03X29055Y226378I0J3937D01*
G01Y246063D02*
G03X25118Y250000I-3937J0D01*
G01X21181D02*
G03X17244Y246063I0J-3937D01*
G01X30157Y397638D02*
G03Y433071I0J17716D01*
G01X37146Y415354D02*
G03I-6989J0D01*
G01X30157Y523622D02*
G03Y559055I0J17716D01*
G01X37146Y541339D02*
G03I-6989J0D01*
G01X17244Y706693D02*
Y726378D01*
G01X29055D02*
Y706693D01*
G01X25118Y702756D02*
X21181D01*
G01Y730315D02*
X25118D01*
G01X17244Y706693D02*
G03X21181Y702756I3937J0D01*
G01X25118D02*
G03X29055Y706693I0J3937D01*
G01Y726378D02*
G03X25118Y730315I-3937J0D01*
G01X21181D02*
G03X17244Y726378I0J-3937D01*
G01X30157Y877953D02*
G03Y913386I0J17716D01*
G01X37146Y895669D02*
G03I-6989J0D01*
G01X98329Y-779523D02*
X99499Y-777963D01*
X100864Y-777183D01*
X102424Y-776923D01*
X104374Y-777443D01*
X105739Y-778743D01*
X106129Y-780303D01*
X105934Y-781863D01*
X105154Y-783163D01*
X101254Y-785763D01*
X99499Y-787583D01*
X98329Y-790183D01*
X97939Y-792523D01*
X106129D01*
G01X93694Y-19685D02*
X1317968D01*
G01X93694D02*
G03X85820I-3937J0D01*
G01X89265D02*
X90249D01*
G01X89757D02*
Y-19291D01*
G01Y-19685D02*
Y-20079D01*
G01X107993Y-7874D02*
X304843D01*
G01X107993Y0D02*
G03Y-7874I0J-3937D01*
G01X77283D02*
G03Y0I0J3937D01*
G01X107993Y480315D02*
G03Y472441I0J-3937D01*
G01X77283D02*
G03Y480315I0J3937D01*
G01X107993Y960630D02*
G03Y952756I0J-3937D01*
G01X77283D02*
G03Y960630I0J3937D01*
G01X107993D02*
X304843D01*
G01X98329Y1398233D02*
X99499Y1399793D01*
X100864Y1400573D01*
X102424Y1400833D01*
X104374Y1400313D01*
X105739Y1399013D01*
X106129Y1397453D01*
X105934Y1395893D01*
X105154Y1394593D01*
X101254Y1391993D01*
X99499Y1390173D01*
X98329Y1387573D01*
X97939Y1385233D01*
X106129D01*
G01X238130Y-492815D02*
X170295D01*
G01X232462Y-496311D02*
X174623Y-517363D01*
G01X177068Y-473405D02*
G03X174232Y-492815I64999J-19409D01*
G01X156925Y-499147D02*
X157575Y-498282D01*
X158332Y-497848D01*
X159199Y-497704D01*
X160281Y-497993D01*
X161039Y-498714D01*
X161256Y-499580D01*
X161147Y-500447D01*
X160714Y-501168D01*
X158549Y-502612D01*
X157575Y-503622D01*
X156925Y-505066D01*
X156708Y-506365D01*
X161256D01*
G01X167643Y-497704D02*
X166777Y-497993D01*
X166127Y-498714D01*
X165694Y-499580D01*
X165369Y-500735D01*
X165261Y-502035D01*
X165369Y-503334D01*
X165694Y-504489D01*
X166127Y-505355D01*
X166777Y-506076D01*
X167643Y-506365D01*
X168509Y-506076D01*
X169159Y-505355D01*
X169592Y-504489D01*
X169917Y-503334D01*
X170025Y-502035D01*
X169917Y-500735D01*
X169592Y-499580D01*
X169159Y-498714D01*
X168509Y-497993D01*
X167643Y-497704D01*
G01X176304Y-506654D02*
X176087Y-506509D01*
Y-506221D01*
X176304Y-506076D01*
X176521Y-506221D01*
Y-506509D01*
X176304Y-506654D01*
G01X184965Y-497704D02*
X184099Y-497993D01*
X183449Y-498714D01*
X183016Y-499580D01*
X182691Y-500735D01*
X182583Y-502035D01*
X182691Y-503334D01*
X183016Y-504489D01*
X183449Y-505355D01*
X184099Y-506076D01*
X184965Y-506365D01*
X185831Y-506076D01*
X186481Y-505355D01*
X186914Y-504489D01*
X187239Y-503334D01*
X187347Y-502035D01*
X187239Y-500735D01*
X186914Y-499580D01*
X186481Y-498714D01*
X185831Y-497993D01*
X184965Y-497704D01*
G01X121252Y-18285D02*
Y-21085D01*
G01X152747Y-18285D02*
Y-21085D01*
G01X209806Y-777373D02*
Y-796310D01*
G01X178323Y-516016D02*
G03X187627Y-533285I63744J23202D01*
G01X187204Y-503478D02*
X188287Y-500591D01*
X189369D01*
X191535Y-506365D01*
X192617D01*
X193700Y-503478D01*
G01X225926Y-441388D02*
X215689D01*
G01X184242Y-18285D02*
Y-21085D01*
G01X215737Y-18285D02*
Y-21085D01*
G01X209806Y1400383D02*
Y1381446D01*
G01X236162Y-494965D02*
Y-496965D01*
G01X242067Y-492815D02*
Y-499115D01*
G01X275532D02*
Y-492815D01*
G01X278091D02*
Y-499115D01*
G01X279469D02*
Y-492815D01*
G01X283406Y-499115D02*
Y-492815D01*
G01X242067Y-499115D02*
X236162Y-496965D01*
G01Y-494965D02*
X242067Y-492815D01*
G01Y-499115D02*
X919863D01*
G01X242067Y-492815D02*
X919863D01*
G01X242067D02*
X919863D01*
G01X236162Y-490781D02*
Y-440679D01*
G01X242067Y-488632D02*
Y-440679D01*
G01X252304Y-441388D02*
X299793D01*
G01X281033Y-441033D02*
Y-432372D01*
X279734Y-434104D01*
G01Y-441033D02*
X282332D01*
G01X289694Y-441322D02*
X289477Y-441177D01*
Y-440889D01*
X289694Y-440744D01*
X289911Y-440889D01*
Y-441177D01*
X289694Y-441322D01*
G01X295973Y-439734D02*
X296623Y-440456D01*
X297381Y-440889D01*
X298355Y-441033D01*
X299329Y-440744D01*
X300087Y-440167D01*
X300629Y-439157D01*
X300737Y-438002D01*
X300520Y-436847D01*
X299979Y-436125D01*
X299221Y-435548D01*
X298463Y-435403D01*
X297705Y-435548D01*
X296731Y-436125D01*
X297056Y-432372D01*
X299979D01*
G01X307016D02*
X306150Y-432661D01*
X305500Y-433382D01*
X305067Y-434248D01*
X304742Y-435403D01*
X304634Y-436703D01*
X304742Y-438002D01*
X305067Y-439157D01*
X305500Y-440023D01*
X306150Y-440744D01*
X307016Y-441033D01*
X307882Y-440744D01*
X308532Y-440023D01*
X308965Y-439157D01*
X309290Y-438002D01*
X309398Y-436703D01*
X309290Y-435403D01*
X308965Y-434248D01*
X308532Y-433382D01*
X307882Y-432661D01*
X307016Y-432372D01*
G01X247232Y-18285D02*
Y-21085D01*
G01X278728Y-18285D02*
Y-21085D01*
G01X317412Y-789403D02*
X318582Y-791223D01*
X320142Y-792263D01*
X321897Y-792523D01*
X323457Y-792263D01*
X325017Y-790963D01*
X325992Y-789403D01*
X326187Y-787843D01*
X325797Y-786023D01*
X324432Y-784723D01*
X323067Y-784203D01*
X321312D01*
G01X323067D02*
X324237Y-783423D01*
X325212Y-782123D01*
X325602Y-780563D01*
X325212Y-779003D01*
X324237Y-777703D01*
X322482Y-776923D01*
X320727Y-777183D01*
X318972Y-778223D01*
G01X296713Y-499115D02*
Y-492815D01*
G01X300650Y-499115D02*
Y-492815D01*
G01X302638D02*
Y-499115D01*
G01X304587D02*
Y-492815D01*
G01X308524Y-499115D02*
Y-492815D01*
G01X316615D02*
Y-499115D01*
G01X335552Y-7874D02*
X532402D01*
G01X304843D02*
G03Y0I0J3937D01*
G01X335552D02*
G03Y-7874I0J-3937D01*
G01X315199Y232232D02*
Y212547D01*
G01X309540Y232232D02*
X320858D01*
G01X335552Y480315D02*
G03Y472441I0J-3937D01*
G01X304843D02*
G03Y480315I0J3937D01*
G01X329869Y717702D02*
Y698017D01*
G01X324210Y717702D02*
X335528D01*
G01X304843Y952756D02*
G03Y960630I0J3937D01*
G01X335552D02*
G03Y952756I0J-3937D01*
G01Y960630D02*
X532402D01*
G01X317412Y1388353D02*
X318582Y1386533D01*
X320142Y1385493D01*
X321897Y1385233D01*
X323457Y1385493D01*
X325017Y1386793D01*
X325992Y1388353D01*
X326187Y1389913D01*
X325797Y1391733D01*
X324432Y1393033D01*
X323067Y1393553D01*
X321312D01*
G01X323067D02*
X324237Y1394333D01*
X325212Y1395633D01*
X325602Y1397193D01*
X325212Y1398753D01*
X324237Y1400053D01*
X322482Y1400833D01*
X320727Y1400573D01*
X318972Y1399533D01*
G01X429474Y-777373D02*
Y-796310D01*
G01X498661Y5906D02*
X451417D01*
G01X498661Y41339D02*
X451417D01*
G01D02*
G03Y5906I0J-17716D01*
G01X498661Y486220D02*
X451417D01*
G01Y521654D02*
G03Y486220I0J-17717D01*
G01X498661Y521654D02*
X451417D01*
G01X429474Y1400383D02*
Y1381446D01*
G01X498661Y5906D02*
G03Y41339I0J17716D01*
G01X506535Y23622D02*
G03I-7874J0D01*
G01X498661Y486220D02*
G03Y521654I0J17717D01*
G01X506535Y503937D02*
G03I-7874J0D01*
G01X543711Y-792523D02*
Y-776923D01*
X536496Y-788103D01*
X546246D01*
G01X563111Y-7874D02*
X725552D01*
G01X563111Y0D02*
G03Y-7874I0J-3937D01*
G01X532402D02*
G03Y0I0J3937D01*
G01X640394Y50591D02*
X567559D01*
G01D02*
Y353740D01*
G01X620709Y120413D02*
X554724D01*
G01X622709Y121909D02*
X573409D01*
G01X568209Y150409D02*
X622709D01*
G01X603609Y154409D02*
X568209D01*
G01Y156909D02*
X603609D01*
G01X609209Y158909D02*
X568209D01*
G01X554724Y120413D02*
Y328406D01*
G01X568209Y127109D02*
Y162909D01*
G01Y127109D02*
G03X573409Y121909I5200J0D01*
G01X568979Y162909D02*
G03X572438I1729J-1019D01*
G01X569459Y161059D02*
X571959D01*
G01Y162759D02*
X569459D01*
G01X588709Y162909D02*
X568209D01*
G01Y170909D02*
X588709D01*
G01X569459Y171059D02*
X571959D01*
G01Y172759D02*
X569459D01*
G01X609209Y174909D02*
X568209D01*
G01X609209Y178909D02*
X568209D01*
G01X569459Y181059D02*
X571959D01*
G01Y182759D02*
X569459D01*
G01X588709Y182909D02*
X568209D01*
G01Y190909D02*
X588709D01*
G01X569459Y191059D02*
X571959D01*
G01Y192759D02*
X569459D01*
G01X609209Y194909D02*
X568209D01*
G01Y196909D02*
X603609D01*
G01X568209Y199409D02*
X588709D01*
G01X569409Y203109D02*
X588709D01*
G01X569409Y205709D02*
X588709D01*
G01X569409Y213109D02*
X588709D01*
G01X569409Y215709D02*
X588709D01*
G01X568209Y199409D02*
Y190909D01*
G01Y182909D02*
Y170909D01*
G01X569409Y215709D02*
Y213109D01*
G01Y205709D02*
Y203109D01*
G01X569459Y192759D02*
Y191059D01*
G01Y182759D02*
Y181059D01*
G01Y172759D02*
Y171059D01*
G01Y162759D02*
Y161059D01*
G01X571959D02*
Y162759D01*
G01Y171059D02*
Y172759D01*
G01Y181059D02*
Y182759D01*
G01Y191059D02*
Y192759D01*
G01X572009Y203109D02*
Y205709D01*
G01Y213109D02*
Y215709D01*
G01X572461Y170909D02*
G03X568956I-1753J981D01*
G01D02*
G03X572461I1753J981D01*
G01X572438Y162909D02*
G03X568979I-1729J-1019D01*
G01X572461Y190909D02*
G03X568956I-1753J981D01*
G01X568979Y182909D02*
G03X572438I1729J-1019D01*
G01X568956Y190909D02*
G03X572461I1753J981D01*
G01X572438Y182909D02*
G03X568979I-1729J-1019D01*
G01X572239Y203109D02*
G03Y205710I-1530J1301D01*
G01D02*
G03Y203109I-1530J-1301D01*
G01Y213109D02*
G03Y215710I-1530J1300D01*
G01D02*
G03Y213109I-1530J-1301D01*
G01X569409Y223109D02*
X588709D01*
G01X569409Y225709D02*
X588709D01*
G01X569409Y233109D02*
X588709D01*
G01X569409Y235709D02*
X588709D01*
G01X569409Y243109D02*
X588709D01*
G01X569409Y245709D02*
X588709D01*
G01Y249409D02*
X568209D01*
G01X603609Y251909D02*
X568209D01*
G01X609209Y253909D02*
X568209D01*
G01X569459Y256059D02*
X571959D01*
G01Y257759D02*
X569459D01*
G01X588709Y257909D02*
X568209D01*
G01Y265909D02*
X588709D01*
G01X569459Y266059D02*
X571959D01*
G01Y267759D02*
X569459D01*
G01X609209Y269909D02*
X568209D01*
G01X609209Y273909D02*
X568209D01*
G01Y277909D02*
Y265909D01*
G01Y257909D02*
Y249409D01*
G01X569409Y245709D02*
Y243109D01*
G01Y235709D02*
Y233109D01*
G01Y225709D02*
Y223109D01*
G01X569459Y267759D02*
Y266059D01*
G01Y257759D02*
Y256059D01*
G01X571959D02*
Y257759D01*
G01Y266059D02*
Y267759D01*
G01X572009Y223109D02*
Y225709D01*
G01Y233109D02*
Y235709D01*
G01Y243109D02*
Y245709D01*
G01X572239Y233109D02*
G03Y235710I-1530J1300D01*
G01Y223109D02*
G03Y225710I-1530J1300D01*
G01Y235710D02*
G03Y233109I-1530J-1301D01*
G01Y225710D02*
G03Y223109I-1530J-1301D01*
G01Y243109D02*
G03Y245710I-1530J1300D01*
G01X572438Y265909D02*
G03X568979I-1729J1020D01*
G01X568956Y257909D02*
G03X572461I1753J-980D01*
G01X572239Y245710D02*
G03Y243109I-1530J-1301D01*
G01X568979Y265909D02*
G03X572438I1729J1020D01*
G01X572461Y257909D02*
G03X568956I-1753J-980D01*
G01X569459Y276059D02*
X571959D01*
G01Y277759D02*
X569459D01*
G01X588709Y277909D02*
X568209D01*
G01Y285909D02*
X588709D01*
G01X569459Y286059D02*
X571959D01*
G01Y287759D02*
X569459D01*
G01X609209Y289909D02*
X568209D01*
G01Y291909D02*
X603609D01*
G01Y294409D02*
X568209D01*
G01X622709Y298409D02*
X568209D01*
G01X622709Y326909D02*
X573409D01*
G01X554724Y328406D02*
X620709D01*
G01X568209Y285909D02*
Y321709D01*
G01X569459Y287759D02*
Y286059D01*
G01Y277759D02*
Y276059D01*
G01X571959D02*
Y277759D01*
G01Y286059D02*
Y287759D01*
G01X568956Y277909D02*
G03X572461I1753J-980D01*
G01D02*
G03X568956I-1753J-980D01*
G01X573409Y326909D02*
G03X568209Y321709I0J-5200D01*
G01X572438Y285909D02*
G03X568979I-1729J1020D01*
G01D02*
G03X572438I1729J1020D01*
G01X627391Y353740D02*
X545906D01*
G01X627391D02*
X545906D01*
G01X627391Y378543D02*
X545906D01*
G01X627391D02*
X545906D01*
G01X541969Y357677D02*
Y374606D01*
G01Y357677D02*
Y374606D01*
G01X567559Y402165D02*
Y378543D01*
G01X545906D02*
G03X541969Y374606I0J-3937D01*
G01Y357677D02*
G03X545906Y353740I3937J0D01*
G01X541969Y357677D02*
G03X545906Y353740I3937J0D01*
G01Y378543D02*
G03X541969Y374606I0J-3937D01*
G01X567559Y402165D02*
X640394D01*
G01X589213Y431102D02*
X541969D01*
G01Y466535D02*
G03Y431102I0J-17716D01*
G01X589213Y466535D02*
X541969D01*
G01X563111Y480315D02*
G03Y472441I0J-3937D01*
G01X532402D02*
G03Y480315I0J3937D01*
G01X627391Y834055D02*
X545906D01*
G01X627391D02*
X545906D01*
G01X541969Y837992D02*
Y854921D01*
G01Y837992D02*
Y854921D01*
G01Y837992D02*
G03X545906Y834055I3937J0D01*
G01X541969Y837992D02*
G03X545906Y834055I3937J0D01*
G01X627391Y858858D02*
X545906D01*
G01X627391D02*
X545906D01*
G01D02*
G03X541969Y854921I0J-3937D01*
G01X545906Y858858D02*
G03X541969Y854921I0J-3937D01*
G01X589213Y911417D02*
X541969D01*
G01X589213Y946850D02*
X541969D01*
G01D02*
G03Y911417I0J-17717D01*
G01X563111Y960630D02*
G03Y952756I0J-3937D01*
G01X532402D02*
G03Y960630I0J3937D01*
G01X563111D02*
X725552D01*
G01X543711Y1385233D02*
Y1400833D01*
X536496Y1389653D01*
X546246D01*
G01X629726Y-777373D02*
X1811321D01*
G01X634526Y73005D02*
X634567Y73013D01*
G01X632913Y71654D02*
X633931D01*
G01X636063Y72638D02*
X632913D01*
G01Y72734D02*
X636063D01*
G01X634345Y72795D02*
X634296D01*
G01X634764D02*
X634567D01*
G01X634559Y72837D02*
X634715D01*
G01Y72963D02*
X634559D01*
G01X634567Y73013D02*
X634715D01*
G01X632913Y73126D02*
X636063D01*
G01X634296Y73189D02*
X634345D01*
G01X634715D02*
X634764D01*
G01X633110Y73228D02*
X635866D01*
G01X635276Y75197D02*
X633701D01*
G01X633110Y76378D02*
X633701D01*
G01X636063Y76480D02*
X632913D01*
G01X636063Y76872D02*
X632913D01*
G01X636063Y76969D02*
X632913D01*
G01X633931Y77953D02*
X632913D01*
G01X634567Y72795D02*
X634526Y72804D01*
G01X634534Y72846D02*
X634559Y72837D01*
G01X634526Y72804D02*
X634493Y72829D01*
G01X634518Y72862D02*
X634534Y72846D01*
G01X634493Y72829D02*
X634469Y72862D01*
G01X634559Y72963D02*
X634534Y72954D01*
G01X634469Y72862D02*
X634460Y72887D01*
G01X634509D02*
X634518Y72862D01*
G01X632913Y71654D02*
Y77953D01*
G01X633110D02*
Y76378D01*
G01Y71654D02*
Y73228D01*
G01X633701Y75197D02*
Y76378D01*
G01X634296Y72795D02*
Y73189D01*
G01X634345D02*
Y72862D01*
G01X634394Y72921D02*
Y72854D01*
G01X634460Y72887D02*
Y72921D01*
G01X634509Y72913D02*
Y72887D01*
G01X634715Y72837D02*
Y72963D01*
G01Y73013D02*
Y73189D01*
G01X634764D02*
Y72795D01*
G01X634493Y72980D02*
X634526Y73005D01*
G01X634460Y72921D02*
X634469Y72946D01*
G01X634518Y72938D02*
X634509Y72913D01*
G01X634469Y72946D02*
X634493Y72980D01*
G01X634345Y72862D02*
X634394Y72921D01*
G01Y72854D02*
X634345Y72795D01*
G01X634534Y72954D02*
X634518Y72938D01*
G01X633931Y77953D02*
G03X635045I557J196D01*
G01Y71654D02*
G03X633931I-557J-197D01*
G01X636457Y132035D02*
X624646D01*
G01X636457D02*
X624646D01*
G01X620709Y135972D02*
Y312846D01*
G01Y135972D02*
Y312846D01*
G01Y135972D02*
G03X622708Y132545I3937J0D01*
G01X620709Y135972D02*
G03X622675Y132564I3937J0D01*
G01X622708Y132545D02*
G03X624646Y132035I1938J3427D01*
G01X622675Y132564D02*
G03X624646Y132035I1971J3409D01*
G01X603609Y156909D02*
Y154409D01*
G01X609209Y158909D02*
Y174909D01*
G01X620709Y326909D02*
Y121909D01*
G01D02*
Y120413D01*
G01Y135972D02*
Y312846D01*
G01Y135972D02*
Y312846D01*
G01X622709Y298409D02*
Y150409D01*
G01Y145909D02*
Y139909D01*
G01Y150409D02*
Y145909D01*
G01Y139909D02*
Y121909D01*
G01X578979Y162909D02*
G03X582438I1729J-1019D01*
G01X608602Y136909D02*
G03I-7893J0D01*
G01X608209D02*
G03I-7500J0D01*
G01X592717Y161890D02*
G03I-2008J0D01*
G01X602717D02*
G03I-2008J0D01*
G01X620709Y135972D02*
G03X622708Y132545I3937J0D01*
G01X620709Y135972D02*
G03X622675Y132564I3937J0D01*
G01D02*
G03X624646Y132035I1971J3409D01*
G01X605854Y160492D02*
X603492D01*
G01X603743Y160787D02*
X604497D01*
G01X604799D02*
X605854D01*
G01X579459Y161059D02*
X581959D01*
G01X589459D02*
X591959D01*
G01X599459D02*
X601959D01*
G01X604196Y162018D02*
X604045D01*
G01Y162313D02*
X604246D01*
G01Y162707D02*
X603844D01*
G01X601959Y162759D02*
X599459D01*
G01X591959D02*
X589459D01*
G01X581959D02*
X579459D01*
G01X605854Y163002D02*
X603894D01*
G01X603492Y163297D02*
X605854D01*
G01X579459Y171059D02*
X581959D01*
G01X589459D02*
X591959D01*
G01X599459D02*
X601959D01*
G01Y172759D02*
X599459D01*
G01X591959D02*
X589459D01*
G01X581959D02*
X579459D01*
G01Y181059D02*
X581959D01*
G01X589459D02*
X591959D01*
G01X599459D02*
X601959D01*
G01Y182759D02*
X599459D01*
G01X591959D02*
X589459D01*
G01X581959D02*
X579459D01*
G01Y191059D02*
X581959D01*
G01X589459D02*
X591959D01*
G01X599459D02*
X601959D01*
G01Y192759D02*
X599459D01*
G01X591959D02*
X589459D01*
G01X581959D02*
X579459D01*
G01X610009Y199409D02*
X588709D01*
G01Y203109D02*
X610009D01*
G01X588709Y205709D02*
X610009D01*
G01X588709Y213109D02*
X610009D01*
G01X588709Y215709D02*
X610009D01*
G01X604346Y161969D02*
X604196Y162018D01*
G01X604246Y162313D02*
X604397Y162264D01*
G01D02*
X604598Y162116D01*
G01X603844Y162707D02*
X603492Y163002D01*
G01X603894D02*
X604246Y162707D01*
G01X603894Y162264D02*
X604045Y162313D01*
G01Y162018D02*
X603894Y161969D01*
G01X604447Y161870D02*
X604346Y161969D01*
G01X604598Y162116D02*
X604748Y161919D01*
G01X603693Y162116D02*
X603894Y162264D01*
G01X604497Y161722D02*
X604447Y161870D01*
G01X579409Y215709D02*
Y213109D01*
G01Y205709D02*
Y203109D01*
G01X579459Y192759D02*
Y191059D01*
G01Y182759D02*
Y181059D01*
G01Y172759D02*
Y171059D01*
G01Y162759D02*
Y161059D01*
G01X581959D02*
Y162759D01*
G01Y171059D02*
Y172759D01*
G01Y181059D02*
Y182759D01*
G01Y191059D02*
Y192759D01*
G01X582009Y203109D02*
Y205709D01*
G01Y213109D02*
Y215709D01*
G01X588709Y249409D02*
Y199409D01*
G01Y190909D02*
Y182909D01*
G01Y170909D02*
Y162909D01*
G01X589409Y215709D02*
Y213109D01*
G01Y205709D02*
Y203109D01*
G01X589459Y192759D02*
Y191059D01*
G01Y182759D02*
Y181059D01*
G01Y172759D02*
Y171059D01*
G01Y162759D02*
Y161059D01*
G01X591959D02*
Y162759D01*
G01Y171059D02*
Y172759D01*
G01Y181059D02*
Y182759D01*
G01Y191059D02*
Y192759D01*
G01X592009Y203109D02*
Y205709D01*
G01Y213109D02*
Y215709D01*
G01X603543Y161919D02*
X603693Y162116D01*
G01X603894Y161969D02*
X603794Y161870D01*
G01X604748Y161919D02*
X604799Y161673D01*
G01X599409Y215709D02*
Y213109D01*
G01Y205709D02*
Y203109D01*
G01X599459Y192759D02*
Y191059D01*
G01Y182759D02*
Y181059D01*
G01Y172759D02*
Y171059D01*
G01Y162759D02*
Y161059D01*
G01X601959D02*
Y162759D01*
G01Y171059D02*
Y172759D01*
G01Y181059D02*
Y182759D01*
G01Y191059D02*
Y192759D01*
G01X602009Y203109D02*
Y205709D01*
G01Y213109D02*
Y215709D01*
G01X603492Y160492D02*
Y161673D01*
G01Y163002D02*
Y163297D01*
G01X603609Y199409D02*
Y196909D01*
G01X603743Y161722D02*
Y160787D01*
G01X604497D02*
Y161722D01*
G01X604799Y161673D02*
Y160787D01*
G01X605854Y163297D02*
Y163002D01*
G01Y160787D02*
Y160492D01*
G01X609209Y178909D02*
Y194909D01*
G01X610009Y249409D02*
Y199409D01*
G01X603492Y161673D02*
X603543Y161919D01*
G01X603794Y161870D02*
X603743Y161722D01*
G01X582461Y170909D02*
G03X578956I-1753J981D01*
G01D02*
G03X582461I1752J981D01*
G01X582438Y162909D02*
G03X578979I-1730J-1019D01*
G01X592717Y171890D02*
G03I-2008J0D01*
G01X602717D02*
G03I-2008J0D01*
G01X582461Y190909D02*
G03X578956I-1753J981D01*
G01X578979Y182909D02*
G03X582438I1729J-1019D01*
G01X578956Y190909D02*
G03X582461I1752J981D01*
G01X582438Y182909D02*
G03X578979I-1730J-1019D01*
G01X582239Y203109D02*
G03Y205710I-1530J1301D01*
G01X579217Y205753D02*
G03X579179Y203109I1492J-1344D01*
G01X582239Y205710D02*
G03X579217Y205753I-1530J-1301D01*
G01X579179Y203109D02*
G03X582239I1530J1300D01*
G01Y213109D02*
G03Y215710I-1530J1300D01*
G01X579217Y215753D02*
G03X579179Y213109I1492J-1344D01*
G01X582239Y215710D02*
G03X579217Y215753I-1530J-1301D01*
G01X579179Y213109D02*
G03X582239I1530J1300D01*
G01X592717Y181890D02*
G03I-2008J0D01*
G01Y191890D02*
G03I-2008J0D01*
G01Y204409D02*
G03I-2008J0D01*
G01X602717Y191890D02*
G03I-2008J0D01*
G01Y181890D02*
G03I-2008J0D01*
G01Y204409D02*
G03I-2008J0D01*
G01X592717Y214409D02*
G03I-2008J0D01*
G01X602717D02*
G03I-2008J0D01*
G01X588709Y223109D02*
X610009D01*
G01X588709Y225709D02*
X610009D01*
G01X588709Y233109D02*
X610009D01*
G01X588709Y235709D02*
X610009D01*
G01X588709Y243109D02*
X610009D01*
G01X588709Y245709D02*
X610009D01*
G01Y249409D02*
X588709D01*
G01X579459Y256059D02*
X581959D01*
G01X589459D02*
X591959D01*
G01X599459D02*
X601959D01*
G01Y257759D02*
X599459D01*
G01X591959D02*
X589459D01*
G01X581959D02*
X579459D01*
G01Y266059D02*
X581959D01*
G01X589459D02*
X591959D01*
G01X599459D02*
X601959D01*
G01Y267759D02*
X599459D01*
G01X591959D02*
X589459D01*
G01X581959D02*
X579459D01*
G01X579409Y245709D02*
Y243109D01*
G01Y235709D02*
Y233109D01*
G01Y225709D02*
Y223109D01*
G01X579459Y267759D02*
Y266059D01*
G01Y257759D02*
Y256059D01*
G01X581959D02*
Y257759D01*
G01Y266059D02*
Y267759D01*
G01X582009Y223109D02*
Y225709D01*
G01Y233109D02*
Y235709D01*
G01Y243109D02*
Y245709D01*
G01X588709Y265909D02*
Y257909D01*
G01X589409Y245709D02*
Y243109D01*
G01Y235709D02*
Y233109D01*
G01Y225709D02*
Y223109D01*
G01X589459Y267759D02*
Y266059D01*
G01Y257759D02*
Y256059D01*
G01X591959D02*
Y257759D01*
G01Y266059D02*
Y267759D01*
G01X592009Y223109D02*
Y225709D01*
G01Y233109D02*
Y235709D01*
G01Y243109D02*
Y245709D01*
G01X599409D02*
Y243109D01*
G01Y235709D02*
Y233109D01*
G01Y225709D02*
Y223109D01*
G01X599459Y267759D02*
Y266059D01*
G01Y257759D02*
Y256059D01*
G01X601959D02*
Y257759D01*
G01Y266059D02*
Y267759D01*
G01X602009Y223109D02*
Y225709D01*
G01Y233109D02*
Y235709D01*
G01Y243109D02*
Y245709D01*
G01X603609Y251909D02*
Y249409D01*
G01X609209Y253909D02*
Y269909D01*
G01Y273909D02*
Y289909D01*
G01X582239Y233109D02*
G03Y235710I-1530J1300D01*
G01X579217Y235753D02*
G03X579179Y233109I1492J-1344D01*
G01X582239Y223109D02*
G03Y225710I-1530J1300D01*
G01X579217Y225753D02*
G03X579179Y223109I1492J-1344D01*
G01X582239Y235710D02*
G03X579217Y235753I-1530J-1301D01*
G01X579179Y233109D02*
G03X582239I1530J1300D01*
G01Y225710D02*
G03X579217Y225753I-1530J-1301D01*
G01X579179Y223109D02*
G03X582239I1530J1300D01*
G01X592717Y234409D02*
G03I-2008J0D01*
G01Y224409D02*
G03I-2008J0D01*
G01X602717Y234409D02*
G03I-2008J0D01*
G01Y224409D02*
G03I-2008J0D01*
G01X582239Y243109D02*
G03Y245710I-1530J1300D01*
G01X579217Y245753D02*
G03X579179Y243109I1492J-1344D01*
G01X582438Y265909D02*
G03X578979I-1730J1020D01*
G01X578956Y257909D02*
G03X582461I1752J-980D01*
G01X582239Y245710D02*
G03X579217Y245753I-1530J-1301D01*
G01X579179Y243109D02*
G03X582239I1530J1300D01*
G01X578979Y265909D02*
G03X582438I1729J1020D01*
G01X582461Y257909D02*
G03X578956I-1753J-980D01*
G01X592717Y256929D02*
G03I-2008J0D01*
G01Y244409D02*
G03I-2008J0D01*
G01Y266929D02*
G03I-2008J0D01*
G01X602717Y256929D02*
G03I-2008J0D01*
G01Y244409D02*
G03I-2008J0D01*
G01Y266929D02*
G03I-2008J0D01*
G01X620709Y312657D02*
Y311161D01*
G01X636457Y316783D02*
X624646D01*
G01X636457D02*
X624646D01*
G01X622708Y316274D02*
G03X620709Y312846I1938J-3427D01*
G01X622675Y316255D02*
G03X620709Y312846I1971J-3408D01*
G01X624646Y316783D02*
G03X622708Y316274I-2J-3937D01*
G01X624646Y316783D02*
G03X622675Y316255I-1J-3937D01*
G01X579459Y276059D02*
X581959D01*
G01X589459D02*
X591959D01*
G01X599459D02*
X601959D01*
G01Y277759D02*
X599459D01*
G01X591959D02*
X589459D01*
G01X581959D02*
X579459D01*
G01Y286059D02*
X581959D01*
G01X589459D02*
X591959D01*
G01X599459D02*
X601959D01*
G01Y287759D02*
X599459D01*
G01X591959D02*
X589459D01*
G01X581959D02*
X579459D01*
G01D02*
Y286059D01*
G01Y277759D02*
Y276059D01*
G01X581959D02*
Y277759D01*
G01Y286059D02*
Y287759D01*
G01X588709Y285909D02*
Y277909D01*
G01X589459Y287759D02*
Y286059D01*
G01Y277759D02*
Y276059D01*
G01X591959D02*
Y277759D01*
G01Y286059D02*
Y287759D01*
G01X599459D02*
Y286059D01*
G01Y277759D02*
Y276059D01*
G01X601959D02*
Y277759D01*
G01Y286059D02*
Y287759D01*
G01X603609Y294409D02*
Y291909D01*
G01X620709Y328406D02*
Y326909D01*
G01X622709Y308909D02*
Y302909D01*
G01D02*
Y298409D01*
G01Y308909D02*
Y326909D01*
G01X578956Y277909D02*
G03X582461I1752J-980D01*
G01D02*
G03X578956I-1753J-980D01*
G01X582438Y285909D02*
G03X578979I-1730J1020D01*
G01D02*
G03X582438I1729J1020D01*
G01X592717Y276929D02*
G03I-2008J0D01*
G01Y286929D02*
G03I-2008J0D01*
G01X602717D02*
G03I-2008J0D01*
G01Y276929D02*
G03I-2008J0D01*
G01X608602Y311909D02*
G03I-7893J0D01*
G01X608209D02*
G03I-7500J0D01*
G01X622708Y316274D02*
G03X620709Y312846I1938J-3427D01*
G01X622675Y316255D02*
G03X620709Y312846I1971J-3408D01*
G01X624646Y316783D02*
G03X622675Y316255I-1J-3937D01*
G01X629574Y379204D02*
X638641Y385248D01*
G01X629574Y379204D02*
X638641Y385248D01*
G01X601024Y375984D02*
X624646D01*
G01X620709Y379921D02*
X604961D01*
G01X638641Y347035D02*
X629574Y353079D01*
G01X638641Y347035D02*
X629574Y353079D01*
G01X601024Y398031D02*
Y375984D01*
G01X604961Y379921D02*
Y394094D01*
G01X605669Y379921D02*
Y391142D01*
G01X610000D02*
Y379921D01*
G01X615669Y391142D02*
Y379921D01*
G01X620000D02*
Y391142D01*
G01X620709Y394094D02*
Y379921D01*
G01X624646Y375984D02*
Y398031D01*
G01X629574Y353079D02*
G03X627391Y353740I-2183J-3276D01*
G01X629574Y353079D02*
G03X627391Y353740I-2183J-3276D01*
G01Y378543D02*
G03X629574Y379205I-2J3937D01*
G01X627391Y378543D02*
G03X629574Y379205I-2J3937D01*
G01X601024Y334252D02*
X624646D01*
G01X620709Y338189D02*
X604961D01*
G01X620000Y349409D02*
X615669D01*
G01X605669D02*
X610000D01*
G01X604961Y352362D02*
X620709D01*
G01X624646Y356299D02*
X601024D01*
G01D02*
Y334252D01*
G01X604961Y338189D02*
Y352362D01*
G01X605669Y338189D02*
Y349409D01*
G01X610000D02*
Y338189D01*
G01X615669Y349409D02*
Y338189D01*
G01X620000D02*
Y349409D01*
G01X620709Y352362D02*
Y338189D01*
G01X624646Y334252D02*
Y356299D01*
G01X620000Y391142D02*
X615669D01*
G01X605669D02*
X610000D01*
G01X604961Y394094D02*
X620709D01*
G01X624646Y398031D02*
X601024D01*
G01X589213Y431102D02*
G03Y466535I0J17716D01*
G01X597087Y448819D02*
G03I-7874J0D01*
G01X636457Y612350D02*
X624646D01*
G01X636457D02*
X624646D01*
G01X620709Y616287D02*
Y793161D01*
G01Y616287D02*
Y793161D01*
G01Y616287D02*
G03X622708Y612860I3937J0D01*
G01X620709Y616287D02*
G03X622675Y612879I3937J0D01*
G01X622708Y612860D02*
G03X624646Y612350I1938J3427D01*
G01X622675Y612879D02*
G03X624646Y612350I1971J3409D01*
G01X638641Y827350D02*
X629574Y833394D01*
G01X638641Y827350D02*
X629574Y833394D01*
G01D02*
G03X627391Y834055I-2184J-3276D01*
G01X629574Y833394D02*
G03X627391Y834055I-2184J-3276D01*
G01X636457Y797098D02*
X624646D01*
G01X636457D02*
X624646D01*
G01X622708Y796589D02*
G03X620709Y793161I1938J-3427D01*
G01X622675Y796570D02*
G03X620709Y793161I1971J-3408D01*
G01X624646Y797098D02*
G03X622708Y796589I-2J-3937D01*
G01X624646Y797098D02*
G03X622675Y796570I-1J-3937D01*
G01X629574Y859520D02*
X638641Y865563D01*
G01X629574Y859520D02*
X638641Y865563D01*
G01X627391Y858858D02*
G03X629574Y859520I-2J3937D01*
G01X627391Y858858D02*
G03X629574Y859520I-2J3937D01*
G01X589213Y911417D02*
G03Y946850I0J17717D01*
G01X597087Y929134D02*
G03I-7874J0D01*
G01X642693Y1003563D02*
X634032D01*
X635764Y1002264D01*
G01X642693D02*
Y1004862D01*
G01Y1012007D02*
X640817Y1012224D01*
X639229Y1012549D01*
X637785Y1012982D01*
X636197Y1013523D01*
X634032Y1014389D01*
Y1010059D01*
G01X640961Y1018503D02*
X641971Y1019153D01*
X642549Y1020019D01*
X642693Y1020993D01*
X642549Y1021859D01*
X641827Y1022726D01*
X640961Y1023267D01*
X640095Y1023375D01*
X639084Y1023159D01*
X638363Y1022401D01*
X638074Y1021643D01*
Y1020668D01*
G01Y1021643D02*
X637641Y1022292D01*
X636919Y1022834D01*
X636053Y1023050D01*
X635187Y1022834D01*
X634465Y1022292D01*
X634032Y1021318D01*
X634176Y1020344D01*
X634754Y1019369D01*
G01X642982Y1029546D02*
X642837Y1029329D01*
X642549D01*
X642404Y1029546D01*
X642549Y1029763D01*
X642837D01*
X642982Y1029546D01*
G01X639084Y1036150D02*
X638074Y1036908D01*
X637496Y1037557D01*
X637208Y1038424D01*
X637496Y1039181D01*
X638074Y1039723D01*
X638940Y1040156D01*
X639950Y1040264D01*
X640817Y1040156D01*
X641683Y1039723D01*
X642404Y1039073D01*
X642693Y1038315D01*
X642404Y1037449D01*
X641538Y1036691D01*
X640239Y1036258D01*
X638796Y1036150D01*
X636919Y1036366D01*
X635908Y1036691D01*
X634898Y1037233D01*
X634176Y1037990D01*
X634032Y1038748D01*
X634321Y1039506D01*
X635042Y1040048D01*
G01X639084Y1044811D02*
X638074Y1045569D01*
X637496Y1046218D01*
X637208Y1047085D01*
X637496Y1047842D01*
X638074Y1048384D01*
X638940Y1048817D01*
X639950Y1048925D01*
X640817Y1048817D01*
X641683Y1048384D01*
X642404Y1047734D01*
X642693Y1046976D01*
X642404Y1046110D01*
X641538Y1045352D01*
X640239Y1044919D01*
X638796Y1044811D01*
X636919Y1045027D01*
X635908Y1045352D01*
X634898Y1045894D01*
X634176Y1046651D01*
X634032Y1047409D01*
X634321Y1048167D01*
X635042Y1048709D01*
G01X649143Y-777373D02*
Y-796310D01*
G01X640394Y112350D02*
Y3937D01*
G01Y112350D02*
Y3937D01*
G01X636457Y0D02*
G03X640394Y3937I0J3937D01*
G01X636457Y0D02*
G03X640394Y3937I0J3937D01*
G01X1284723Y0D02*
X652203D01*
G01X1284723D02*
X652203D01*
G01X648266Y3937D02*
Y83917D01*
G01Y3937D02*
Y83917D01*
G01X699447Y41339D02*
G03Y5906I0J-17716D01*
G01X707321Y23622D02*
G03I-7874J0D01*
G01X648266Y3937D02*
G03X652203Y0I3937J0D01*
G01X648266Y3937D02*
G03X652203Y0I3937J0D01*
G01X648267Y34437D02*
G03X640393I-3937J0D01*
G01X640394Y128098D02*
Y3937D01*
G01Y128098D02*
Y3937D01*
G01X659085Y93237D02*
X650019Y87193D01*
G01X659085Y93237D02*
X650019Y87193D01*
G01X661269Y93898D02*
X742754D01*
G01X661269D02*
X742754D01*
G01X650019Y87193D02*
G03X648266Y83917I2185J-3276D01*
G01X661269Y93898D02*
G03X659085Y93237I0J-3937D01*
G01X661269Y93898D02*
G03X659085Y93237I0J-3937D01*
G01X650019Y87193D02*
G03X648266Y83917I2185J-3276D01*
G01X640393Y65146D02*
G03X648267I3937J0D01*
G01X635045Y71654D02*
X636063D01*
G01X635276Y76378D02*
X635866D01*
G01X636063Y77953D02*
X635045D01*
G01X635276Y76378D02*
Y75197D01*
G01X635866Y73228D02*
Y71654D01*
G01Y76378D02*
Y77953D01*
G01X636063Y71654D02*
Y77953D01*
G01X661269Y118701D02*
X742754D01*
G01X661269D02*
X742754D01*
G01X650019Y125406D02*
X659085Y119362D01*
G01X650019Y125406D02*
X659085Y119362D01*
G01D02*
G03X661269Y118701I2184J3276D01*
G01X648266Y128682D02*
G03X650019Y125406I3937J0D01*
G01X648266Y128682D02*
G03X650019Y125406I3937J0D01*
G01X659085Y119362D02*
G03X661269Y118701I2184J3276D01*
G01X640394Y128098D02*
G03X636457Y132035I-3937J0D01*
G01X640394Y128098D02*
G03X636457Y132035I-3937J0D01*
G01X652203Y155657D02*
X664014D01*
G01X652203D02*
X664014D01*
G01X667951Y336469D02*
Y159594D01*
G01Y336469D02*
Y159594D01*
G01X648266Y128682D02*
Y151720D01*
G01Y128682D02*
Y151720D01*
G01X665952Y156167D02*
G03X667951Y159594I-1938J3427D01*
G01X665985Y156186D02*
G03X667951Y159594I-1971J3408D01*
G01X664014Y155657D02*
G03X665952Y156167I0J3937D01*
G01X652203Y155657D02*
G03X648266Y151720I0J-3937D01*
G01X652203Y155657D02*
G03X648266Y151720I0J-3937D01*
G01X664014Y155657D02*
G03X665985Y156186I0J3938D01*
G01X640394Y343759D02*
Y320720D01*
G01Y343759D02*
Y320720D01*
G01X636457Y316783D02*
G03X640394Y320720I0J3937D01*
G01X636457Y316783D02*
G03X640394Y320720I0J3937D01*
G01Y468504D02*
Y388524D01*
G01Y468504D02*
Y388524D01*
G01Y343759D02*
G03X638641Y347035I-3938J0D01*
G01X640394Y343759D02*
G03X638641Y347035I-3938J0D01*
G01Y385248D02*
G03X640394Y388524I-2185J3276D01*
G01X638641Y385248D02*
G03X640394Y388524I-2185J3276D01*
G01X648266Y360091D02*
Y468504D01*
G01Y360091D02*
Y468504D01*
G01X652203Y340406D02*
X664014D01*
G01X652203D02*
X664014D01*
G01X648266Y344343D02*
Y468504D01*
G01Y344343D02*
Y468504D01*
G01X667951Y336469D02*
G03X665952Y339896I-3937J0D01*
G01X667951Y336469D02*
G03X665985Y339877I-3937J0D01*
G01X648266Y344343D02*
G03X652203Y340406I3937J0D01*
G01X665952Y339896D02*
G03X664014Y340406I-1938J-3427D01*
G01X648266Y344343D02*
G03X652203Y340406I3937J0D01*
G01X665985Y339877D02*
G03X664014Y340406I-1971J-3409D01*
G01X648267Y407295D02*
G03X640393I-3937J0D01*
G01Y438004D02*
G03X648267I3937J0D01*
G01X640394Y468504D02*
G03X636457Y472441I-3937J0D01*
G01X640394Y468504D02*
G03X636457Y472441I-3937J0D01*
G01X640394Y592665D02*
Y484252D01*
G01Y592665D02*
Y484252D01*
G01X636457Y480315D02*
G03X640394Y484252I0J3937D01*
G01X636457Y480315D02*
G03X640394Y484252I0J3937D01*
G01X1284723Y480315D02*
X652203D01*
G01X1284723D02*
X652203D01*
G01X648266Y484252D02*
Y564231D01*
G01Y484252D02*
Y564231D01*
G01X699447Y521654D02*
G03Y486220I0J-17717D01*
G01X707321Y503937D02*
G03I-7874J0D01*
G01X648266Y484252D02*
G03X652203Y480315I3937J0D01*
G01X648266Y484252D02*
G03X652203Y480315I3937J0D01*
G01Y472441D02*
X1284723D01*
G01X652203D02*
X1284723D01*
G01X652203D02*
G03X648266Y468504I0J-3937D01*
G01X652203Y472441D02*
G03X648266Y468504I0J-3937D01*
G01X640394Y608413D02*
Y484252D01*
G01Y608413D02*
Y484252D01*
G01X640393Y545462D02*
G03X648267I3937J0D01*
G01Y514753D02*
G03X640393I-3937J0D01*
G01X659085Y573552D02*
X650019Y567507D01*
G01X659085Y573552D02*
X650019Y567507D01*
G01X661269Y599016D02*
X742754D01*
G01X661269D02*
X742754D01*
G01X661269Y574213D02*
X742754D01*
G01X661269D02*
X742754D01*
G01X650019Y605721D02*
X659085Y599677D01*
G01X650019Y605721D02*
X659085Y599677D01*
G01D02*
G03X661269Y599016I2184J3276D01*
G01X648266Y608997D02*
G03X650019Y605721I3937J0D01*
G01X648266Y608997D02*
G03X650019Y605721I3937J0D01*
G01X659085Y599677D02*
G03X661269Y599016I2184J3276D01*
G01X650019Y567507D02*
G03X648266Y564231I2184J-3276D01*
G01X661269Y574213D02*
G03X659085Y573552I0J-3937D01*
G01X661269Y574213D02*
G03X659085Y573552I0J-3937D01*
G01X650019Y567507D02*
G03X648266Y564231I2184J-3276D01*
G01X640394Y608413D02*
G03X636457Y612350I-3937J0D01*
G01X640394Y608413D02*
G03X636457Y612350I-3937J0D01*
G01X648266Y608997D02*
Y632035D01*
G01Y608997D02*
Y632035D01*
G01X652203Y635972D02*
X664014D01*
G01X652203D02*
X664014D01*
G01X667951Y816783D02*
Y639909D01*
G01Y816783D02*
Y639909D01*
G01X665952Y636482D02*
G03X667951Y639909I-1938J3427D01*
G01X665985Y636501D02*
G03X667951Y639909I-1971J3408D01*
G01X664014Y635972D02*
G03X665952Y636482I0J3937D01*
G01X652203Y635972D02*
G03X648266Y632035I0J-3937D01*
G01X652203Y635972D02*
G03X648266Y632035I0J-3937D01*
G01X664014Y635972D02*
G03X665985Y636501I0J3938D01*
G01X640394Y824074D02*
G03X638641Y827350I-3938J0D01*
G01X640394Y824074D02*
G03X638641Y827350I-3938J0D01*
G01X648266Y840406D02*
Y948819D01*
G01Y840406D02*
Y948819D01*
G01X640394Y824074D02*
Y801035D01*
G01Y824074D02*
Y801035D01*
G01X636457Y797098D02*
G03X640394Y801035I0J3937D01*
G01X636457Y797098D02*
G03X640394Y801035I0J3937D01*
G01X652203Y820720D02*
X664014D01*
G01X652203D02*
X664014D01*
G01X648266Y824657D02*
Y948819D01*
G01Y824657D02*
Y948819D01*
G01X667951Y816783D02*
G03X665952Y820211I-3937J1D01*
G01X667951Y816783D02*
G03X665985Y820192I-3937J1D01*
G01X648266Y824657D02*
G03X652203Y820720I3937J0D01*
G01X665952Y820211D02*
G03X664014Y820720I-1936J-3428D01*
G01X648266Y824657D02*
G03X652203Y820720I3937J0D01*
G01X665985Y820192D02*
G03X664014Y820720I-1970J-3409D01*
G01X640394Y948819D02*
Y868839D01*
G01Y948819D02*
Y868839D01*
G01X638641Y865563D02*
G03X640394Y868839I-2185J3276D01*
G01X638641Y865563D02*
G03X640394Y868839I-2185J3276D01*
G01X648267Y887611D02*
G03X640393I-3937J0D01*
G01X640394Y948819D02*
G03X636457Y952756I-3937J0D01*
G01X640394Y948819D02*
G03X636457Y952756I-3937J0D01*
G01X652203D02*
X1284723D01*
G01X652203D02*
X1284723D01*
G01X652203D02*
G03X648266Y948819I0J-3937D01*
G01X652203Y952756D02*
G03X648266Y948819I0J-3937D01*
G01X640393Y918320D02*
G03X648267I3937J0D01*
G01Y952756D02*
Y1000315D01*
G01X640393Y952756D02*
Y1000315D01*
G01X652693Y1003563D02*
X644032D01*
X645764Y1002264D01*
G01X652693D02*
Y1004862D01*
G01Y1012007D02*
X650817Y1012224D01*
X649229Y1012549D01*
X647785Y1012982D01*
X646197Y1013523D01*
X644032Y1014389D01*
Y1010059D01*
G01X651394Y1018503D02*
X652116Y1019153D01*
X652549Y1019911D01*
X652693Y1020885D01*
X652404Y1021859D01*
X651827Y1022617D01*
X650817Y1023159D01*
X649662Y1023267D01*
X648507Y1023050D01*
X647785Y1022509D01*
X647208Y1021751D01*
X647063Y1020993D01*
X647208Y1020235D01*
X647785Y1019261D01*
X644032Y1019586D01*
Y1022509D01*
G01X652982Y1029546D02*
X652837Y1029329D01*
X652549D01*
X652404Y1029546D01*
X652549Y1029763D01*
X652837D01*
X652982Y1029546D01*
G01X649084Y1036150D02*
X648074Y1036908D01*
X647496Y1037557D01*
X647208Y1038424D01*
X647496Y1039181D01*
X648074Y1039723D01*
X648940Y1040156D01*
X649950Y1040264D01*
X650817Y1040156D01*
X651683Y1039723D01*
X652404Y1039073D01*
X652693Y1038315D01*
X652404Y1037449D01*
X651538Y1036691D01*
X650239Y1036258D01*
X648796Y1036150D01*
X646919Y1036366D01*
X645908Y1036691D01*
X644898Y1037233D01*
X644176Y1037990D01*
X644032Y1038748D01*
X644321Y1039506D01*
X645042Y1040048D01*
G01X649084Y1044811D02*
X648074Y1045569D01*
X647496Y1046218D01*
X647208Y1047085D01*
X647496Y1047842D01*
X648074Y1048384D01*
X648940Y1048817D01*
X649950Y1048925D01*
X650817Y1048817D01*
X651683Y1048384D01*
X652404Y1047734D01*
X652693Y1046976D01*
X652404Y1046110D01*
X651538Y1045352D01*
X650239Y1044919D01*
X648796Y1044811D01*
X646919Y1045027D01*
X645908Y1045352D01*
X644898Y1045894D01*
X644176Y1046651D01*
X644032Y1047409D01*
X644321Y1048167D01*
X645042Y1048709D01*
G01X649143Y1400383D02*
Y1381446D01*
G01X699447Y41339D02*
X746691D01*
G01X699447Y5906D02*
X746691D01*
G01D02*
G03Y41339I0J17716D01*
G01X725552Y-7874D02*
G03Y0I0J3937D01*
G01X746691Y114764D02*
Y97835D01*
G01Y114764D02*
Y97835D01*
G01X742754Y93898D02*
G03X746691Y97835I0J3937D01*
G01X742754Y93898D02*
G03X746691Y97835I0J3937D01*
G01Y114764D02*
G03X742754Y118701I-3937J0D01*
G01X746691Y114764D02*
G03X742754Y118701I-3937J0D01*
G01X699447Y486220D02*
X746691D01*
G01D02*
G03Y521654I0J17717D01*
G01X725552Y472441D02*
G03Y480315I0J3937D01*
G01X699447Y521654D02*
X746691D01*
G01Y595079D02*
Y578150D01*
G01Y595079D02*
Y578150D01*
G01X742754Y574213D02*
G03X746691Y578150I0J3937D01*
G01Y595079D02*
G03X742754Y599016I-3937J0D01*
G01X746691Y595079D02*
G03X742754Y599016I-3937J0D01*
G01Y574213D02*
G03X746691Y578150I0J3937D01*
G01X725552Y952756D02*
G03Y960630I0J3937D01*
G01X756751Y-790183D02*
X757921Y-791483D01*
X759286Y-792263D01*
X761041Y-792523D01*
X762796Y-792003D01*
X764161Y-790963D01*
X765136Y-789143D01*
X765331Y-787063D01*
X764941Y-784983D01*
X763966Y-783683D01*
X762601Y-782643D01*
X761236Y-782383D01*
X759871Y-782643D01*
X758116Y-783683D01*
X758701Y-776923D01*
X763966D01*
G01X770256Y-492815D02*
Y-499115D01*
G01X786004Y-492815D02*
Y-499115D01*
G01X756261Y0D02*
G03Y-7874I0J-3937D01*
G01X953111D02*
X756261D01*
G01X789998Y431102D02*
X837243D01*
G01X789998Y466535D02*
G03Y431102I0J-17716D01*
G01X797872Y448819D02*
G03I-7874J0D01*
G01X789998Y466535D02*
X837243D01*
G01X756261Y480315D02*
G03Y472441I0J-3937D01*
G01X789998Y946850D02*
X837243D01*
G01X789998Y911417D02*
X837243D01*
G01X789998Y946850D02*
G03Y911417I0J-17717D01*
G01X797872Y929134D02*
G03I-7874J0D01*
G01X756261Y960630D02*
G03Y952756I0J-3937D01*
G01X953111Y960630D02*
X756261D01*
G01X756751Y1387573D02*
X757921Y1386273D01*
X759286Y1385493D01*
X761041Y1385233D01*
X762796Y1385753D01*
X764161Y1386793D01*
X765136Y1388613D01*
X765331Y1390693D01*
X764941Y1392773D01*
X763966Y1394073D01*
X762601Y1395113D01*
X761236Y1395373D01*
X759871Y1395113D01*
X758116Y1394073D01*
X758701Y1400833D01*
X763966D01*
G01X848878Y-506315D02*
X851478D01*
G01X858878D02*
X861478D01*
G01X900178Y-492815D02*
X834193D01*
G01X847678Y-488815D02*
X888678D01*
G01X847678Y-484215D02*
X888678D01*
G01X940678Y-470815D02*
X847678D01*
G01X861478Y-468315D02*
X889478D01*
G01X821437Y-499115D02*
Y-492815D01*
G01X825374Y-499115D02*
Y-492815D01*
G01X847678D02*
Y-443315D01*
G01X848878Y-455715D02*
Y-499115D01*
G01D02*
Y-506315D01*
G01X848928Y-499115D02*
Y-506315D01*
G01Y-499115D02*
Y-451215D01*
G01X851428Y-506315D02*
Y-499115D01*
G01D02*
Y-451215D01*
G01X851478Y-506315D02*
Y-499115D01*
G01D02*
Y-458315D01*
G01X852878Y-470815D02*
Y-492815D01*
G01X858878Y-465715D02*
Y-499115D01*
G01D02*
Y-506315D01*
G01X858928Y-499115D02*
Y-506315D01*
G01Y-499115D02*
Y-451215D01*
G01X860807Y-492815D02*
Y-499115D01*
G01X861428Y-506315D02*
Y-499115D01*
G01D02*
Y-451215D01*
G01X861478Y-506315D02*
Y-499115D01*
G01D02*
Y-468315D01*
G01X858878Y-465715D02*
X889478D01*
G01X851478Y-458315D02*
X889478D01*
G01X848878Y-455715D02*
X889478D01*
G01X908178Y-451215D02*
X847678D01*
G01Y-443315D02*
X940678D01*
G01X837243Y431102D02*
G03Y466535I0J17716D01*
G01Y911417D02*
G03Y946850I0J17717D01*
G01X868813Y-777373D02*
Y-796310D01*
G01X939678Y-481315D02*
X908178Y-489015D01*
G01X868878Y-506315D02*
X871478D01*
G01X878878D02*
X881478D01*
G01X902178Y-500715D02*
X940678D01*
G01Y-497715D02*
X908178D01*
G01X940678Y-496015D02*
X908178D01*
G01X904115Y-492815D02*
X880493D01*
G01X904115D02*
X880493D01*
G01X902178D02*
X900178D01*
G01X912382D02*
X912579D01*
G01D02*
X915335D01*
G01D02*
X915532D01*
G01X912382Y-492107D02*
X915532D01*
G01X912382Y-491009D02*
X915532D01*
G01X912382Y-490650D02*
X915532D01*
G01X908178Y-489415D02*
X888678D01*
G01X881478Y-488315D02*
X889478D01*
G01X908178D02*
X935178D01*
G01X908178Y-487915D02*
X888678D01*
G01X878878Y-485715D02*
X889478D01*
G01X908178D02*
X935178D01*
G01X871478Y-478315D02*
X889478D01*
G01X908178D02*
X935178D01*
G01X900178Y-476280D02*
X884430D01*
G01X900178D02*
X884430D01*
G01X868878Y-475715D02*
X889478D01*
G01X908178D02*
X935178D01*
G01X940678Y-473815D02*
X908178D01*
G01Y-468315D02*
X935178D01*
G01X868878Y-475715D02*
Y-499115D01*
G01D02*
Y-506315D01*
G01X868928Y-499115D02*
Y-506315D01*
G01Y-499115D02*
Y-451215D01*
G01X871428Y-506315D02*
Y-499115D01*
G01D02*
Y-451215D01*
G01X871478Y-506315D02*
Y-499115D01*
G01D02*
Y-478315D01*
G01X872284Y-499115D02*
Y-492815D01*
G01X872678Y-470815D02*
Y-492815D01*
G01X876556D02*
Y-499115D01*
G01X878878Y-485715D02*
Y-499115D01*
G01D02*
Y-506315D01*
G01X878928Y-499115D02*
Y-506315D01*
G01Y-499115D02*
Y-451215D01*
G01X881428Y-506315D02*
Y-499115D01*
G01D02*
Y-451215D01*
G01X881478Y-506315D02*
Y-499115D01*
G01D02*
Y-488315D01*
G01X883078Y-488815D02*
Y-492815D01*
G01X884430Y-476280D02*
Y-492815D01*
G01D02*
Y-476280D01*
G01X887678Y-470815D02*
Y-492815D01*
G01X888071Y-499115D02*
Y-492815D01*
G01X888678D02*
Y-487915D01*
G01Y-484215D02*
Y-451215D01*
G01X889478Y-492815D02*
Y-447315D01*
G01X900178Y-499115D02*
Y-492815D01*
G01D02*
Y-476280D01*
G01Y-492815D02*
Y-476280D01*
G01X902178Y-499115D02*
Y-500715D01*
G01Y-499115D02*
Y-492815D01*
G01D02*
Y-443315D01*
G01X904115Y-499115D02*
Y-492815D01*
G01X906859D02*
Y-499115D01*
G01X908178Y-497715D02*
Y-446315D01*
G01X909043Y-492815D02*
Y-499115D01*
G01X912382Y-492815D02*
Y-490650D01*
G01X913400Y-492815D02*
Y-492107D01*
G01X914514Y-492815D02*
Y-492107D01*
G01X915532Y-492815D02*
Y-490650D01*
G01X915926Y-499115D02*
Y-492815D01*
G01X918109D02*
Y-499115D01*
G01X919863D02*
Y-492815D01*
G01X908178Y-495715D02*
G03X910178Y-497715I2000J0D01*
G01X920109Y-492815D02*
X998031D01*
G01X920109Y-499115D02*
X998031D01*
G01X908178Y-465715D02*
X935178D01*
G01X908178Y-458315D02*
X935178D01*
G01X908178Y-455715D02*
X935178D01*
G01X908178Y-448015D02*
X940678D01*
G01X889478Y-447315D02*
X868178D01*
G01X940678Y-446315D02*
X908178D01*
G01Y-454615D02*
X939678Y-460715D01*
G01X868178Y-451215D02*
Y-443315D01*
G01X910178Y-446315D02*
G03X908178Y-448315I0J-2000D01*
G01X868813Y1400383D02*
Y1381446D01*
G01X977005Y-786023D02*
X978370Y-784203D01*
X979540Y-783163D01*
X981100Y-782643D01*
X982465Y-783163D01*
X983440Y-784203D01*
X984220Y-785763D01*
X984415Y-787583D01*
X984220Y-789143D01*
X983440Y-790703D01*
X982270Y-792003D01*
X980905Y-792523D01*
X979345Y-792003D01*
X977980Y-790443D01*
X977200Y-788103D01*
X977005Y-785503D01*
X977395Y-782123D01*
X977980Y-780303D01*
X978955Y-778483D01*
X980320Y-777183D01*
X981685Y-776923D01*
X983050Y-777443D01*
X984025Y-778743D01*
G01X923672Y-470815D02*
Y-443315D01*
G01X924801D02*
Y-470815D01*
G01X926572Y-443315D02*
Y-470815D01*
G01X935178Y-488315D02*
Y-485715D01*
G01Y-478315D02*
Y-475715D01*
G01Y-468315D02*
Y-465715D01*
G01X939678Y-460715D02*
Y-481315D01*
G01X940678Y-500715D02*
Y-443315D01*
G01X935178Y-458315D02*
Y-455715D01*
G01X953111Y-7874D02*
G03Y0I0J3937D01*
G01Y472441D02*
G03Y480315I0J3937D01*
G01Y952756D02*
G03Y960630I0J3937D01*
G01X977005Y1391733D02*
X978370Y1393553D01*
X979540Y1394593D01*
X981100Y1395113D01*
X982465Y1394593D01*
X983440Y1393553D01*
X984220Y1391993D01*
X984415Y1390173D01*
X984220Y1388613D01*
X983440Y1387053D01*
X982270Y1385753D01*
X980905Y1385233D01*
X979345Y1385753D01*
X977980Y1387313D01*
X977200Y1389653D01*
X977005Y1392253D01*
X977395Y1395633D01*
X977980Y1397453D01*
X978955Y1399273D01*
X980320Y1400573D01*
X981685Y1400833D01*
X983050Y1400313D01*
X984025Y1399013D01*
G01X997322Y-509351D02*
Y-519587D01*
G01Y-482579D02*
Y-449981D01*
G01X996968Y-468741D02*
X988307D01*
X990039Y-470040D01*
G01X996968D02*
Y-467442D01*
G01X997257Y-460080D02*
X997112Y-460297D01*
X996824D01*
X996679Y-460080D01*
X996824Y-459863D01*
X997112D01*
X997257Y-460080D01*
G01X993359Y-453476D02*
X992349Y-452718D01*
X991771Y-452069D01*
X991483Y-451202D01*
X991771Y-450445D01*
X992349Y-449903D01*
X993215Y-449470D01*
X994225Y-449362D01*
X995092Y-449470D01*
X995958Y-449903D01*
X996679Y-450553D01*
X996968Y-451311D01*
X996679Y-452177D01*
X995813Y-452935D01*
X994514Y-453368D01*
X993071Y-453476D01*
X991194Y-453260D01*
X990183Y-452935D01*
X989173Y-452393D01*
X988451Y-451636D01*
X988307Y-450878D01*
X988596Y-450120D01*
X989317Y-449578D01*
G01X988307Y-442758D02*
X988596Y-443624D01*
X989317Y-444274D01*
X990183Y-444707D01*
X991338Y-445032D01*
X992638Y-445140D01*
X993937Y-445032D01*
X995092Y-444707D01*
X995958Y-444274D01*
X996679Y-443624D01*
X996968Y-442758D01*
X996679Y-441892D01*
X995958Y-441242D01*
X995092Y-440809D01*
X993937Y-440484D01*
X992638Y-440376D01*
X991338Y-440484D01*
X990183Y-440809D01*
X989317Y-441242D01*
X988596Y-441892D01*
X988307Y-442758D01*
G01X983820Y0D02*
G03Y-7874I0J-3937D01*
G01X1180670D02*
X983820D01*
G01X1000886Y233575D02*
Y253260D01*
G01X1006545Y233575D02*
X995227D01*
G01X983820Y480315D02*
G03Y472441I0J-3937D01*
G01X1005473Y678332D02*
Y698017D01*
G01X1011132Y678332D02*
X999814D01*
G01X983820Y960630D02*
G03Y952756I0J-3937D01*
G01X1180670Y960630D02*
X983820D01*
G01X1088482Y-777373D02*
Y-796310D01*
G01Y1400383D02*
Y1381446D01*
G01X1199990Y-792523D02*
X1200380Y-789143D01*
X1200965Y-786283D01*
X1201745Y-783683D01*
X1202720Y-780823D01*
X1204280Y-776923D01*
X1196480D01*
G01X1180670Y-7874D02*
G03Y0I0J3937D01*
G01Y472441D02*
G03Y480315I0J3937D01*
G01Y952756D02*
G03Y960630I0J3937D01*
G01X1199990Y1385233D02*
X1200380Y1388613D01*
X1200965Y1391473D01*
X1201745Y1394073D01*
X1202720Y1396933D01*
X1204280Y1400833D01*
X1196480D01*
G01X1258502Y39370D02*
X1288660D01*
G01X1258502Y74803D02*
G03Y39370I0J-17716D01*
G01X1211380Y-7874D02*
X1284723D01*
G01X1211380Y0D02*
G03Y-7874I0J-3937D01*
G01X1258502Y74803D02*
X1288660D01*
G01X1265491Y57087D02*
G03I-6989J0D01*
G01X1259605Y226378D02*
Y246063D01*
G01X1263542Y250000D02*
G03X1259605Y246063I0J-3937D01*
G01Y226378D02*
G03X1263542Y222441I3937J0D01*
G01X1258502Y429134D02*
X1288660D01*
G01X1258502Y393701D02*
X1288660D01*
G01X1258502Y429134D02*
G03Y393701I0J-17716D01*
G01X1265491Y411417D02*
G03I-6989J0D01*
G01X1211380Y480315D02*
G03Y472441I0J-3937D01*
G01X1258502Y555118D02*
X1288660D01*
G01X1258502Y519685D02*
X1288660D01*
G01X1258502Y555118D02*
G03Y519685I0J-17716D01*
G01X1265491Y537402D02*
G03I-6989J0D01*
G01X1259605Y706693D02*
Y726378D01*
G01X1263542Y730315D02*
G03X1259605Y726378I0J-3937D01*
G01Y706693D02*
G03X1263542Y702756I3937J0D01*
G01X1258502Y874016D02*
X1288660D01*
G01X1258502Y909449D02*
G03Y874016I0J-17716D01*
G01X1265491Y891732D02*
G03I-6989J0D01*
G01X1258502Y909449D02*
X1288660D01*
G01X1211380Y960630D02*
G03Y952756I0J-3937D01*
G01Y960630D02*
X1284723D01*
G01X1308151Y-777373D02*
Y-796310D01*
G01X1317968Y-19685D02*
G03X1331968Y-5685I0J14000D01*
G01X1288660Y102559D02*
Y3937D01*
G01Y102559D02*
Y3937D01*
G01X1284723Y0D02*
G03X1288660Y3937I0J3937D01*
G01X1284723Y0D02*
G03X1288660Y3937I0J3937D01*
G01X1284723Y-7874D02*
G03X1296534Y3937I0J11811D01*
G01D02*
Y45847D01*
G01D02*
G03X1288660I-3937J0D01*
G01X1316572Y15749D02*
G03X1307990I-4291J0D01*
G01D02*
G03X1316572I4291J0D01*
G01X1292597Y106496D02*
G03X1288660Y102559I0J-3937D01*
G01X1292597Y106496D02*
G03X1288660Y102559I0J-3937D01*
G01X1331968Y98622D02*
X1296534D01*
G01D02*
Y71044D01*
G01X1288660D02*
G03X1296534I3937J0D01*
G01X1300195Y58466D02*
X1295195D01*
G01Y55966D02*
X1300195D01*
G01X1305695Y50466D02*
X1289695D01*
G01X1300195Y60966D02*
Y55966D01*
G01X1305695Y50466D02*
Y66466D01*
G01X1295195Y55966D02*
Y60966D01*
G01X1297695Y55966D02*
Y60966D01*
G01X1300195D02*
X1295195D01*
G01X1289695Y66466D02*
Y50466D01*
G01X1305695Y66466D02*
X1289695D01*
G01X1306376Y161811D02*
Y158661D01*
G01Y156811D02*
Y153661D01*
G01Y151811D02*
Y148661D01*
G01Y146811D02*
Y143661D01*
G01Y141811D02*
Y138661D01*
G01Y136811D02*
Y133661D01*
G01Y131811D02*
Y128661D01*
G01Y126811D02*
Y123661D01*
G01Y121811D02*
Y118661D01*
G01Y116811D02*
Y113661D01*
G01Y158661D02*
X1326061D01*
G01Y156811D02*
X1306376D01*
G01Y153661D02*
X1326061D01*
G01Y151811D02*
X1306376D01*
G01Y148661D02*
X1326061D01*
G01Y146811D02*
X1306376D01*
G01Y143661D02*
X1326061D01*
G01Y141811D02*
X1306376D01*
G01Y138661D02*
X1326061D01*
G01Y136811D02*
X1306376D01*
G01Y133661D02*
X1326061D01*
G01Y131811D02*
X1306376D01*
G01Y128661D02*
X1326061D01*
G01Y126811D02*
X1306376D01*
G01Y123661D02*
X1326061D01*
G01Y121811D02*
X1306376D01*
G01Y118661D02*
X1326061D01*
G01Y116811D02*
X1306376D01*
G01Y113661D02*
X1326061D01*
G01X1292597Y106496D02*
X1326061D01*
G01X1292597D02*
X1326061D01*
G01X1306376Y171811D02*
Y168661D01*
G01Y166811D02*
Y163661D01*
G01X1301258Y237638D02*
Y200394D01*
G01Y197638D02*
Y180394D01*
G01Y200394D02*
X1326061D01*
G01Y197638D02*
X1301258D01*
G01Y180394D02*
X1326061D01*
G01D02*
X1290038D01*
G01X1301258D02*
X1290038D01*
G01X1326061Y177638D02*
X1290038D01*
G01X1326061D02*
X1290038D01*
G01X1326061Y171811D02*
X1306376D01*
G01Y168661D02*
X1326061D01*
G01Y166811D02*
X1306376D01*
G01Y163661D02*
X1326061D01*
G01Y161811D02*
X1306376D01*
G01X1290038Y180394D02*
G03Y177638I0J-1378D01*
G01Y180394D02*
G03Y177638I0J-1378D01*
G01X1301258Y277638D02*
Y240394D01*
G01D02*
X1326061D01*
G01Y237638D02*
X1301258D01*
G01X1271416Y246063D02*
Y226378D01*
G01X1263542Y250000D02*
X1267479D01*
G01Y222441D02*
X1263542D01*
G01X1271416Y246063D02*
G03X1267479Y250000I-3937J0D01*
G01Y222441D02*
G03X1271416Y226378I0J3937D01*
G01X1301258Y357638D02*
Y320394D01*
G01Y317638D02*
Y280394D01*
G01Y320394D02*
X1326061D01*
G01Y317638D02*
X1301258D01*
G01Y280394D02*
X1326061D01*
G01Y277638D02*
X1301258D01*
G01X1288660Y468504D02*
Y365472D01*
G01Y468504D02*
Y365472D01*
G01X1326061Y361535D02*
X1292597D01*
G01X1326061D02*
X1292597D01*
G01X1326061Y357638D02*
X1301258D01*
G01X1288660Y365472D02*
G03X1292597Y361535I3937J0D01*
G01X1288660Y365472D02*
G03X1292597Y361535I3937J0D01*
G01X1331968Y369409D02*
X1296534D01*
G01D02*
Y396985D01*
G01D02*
G03X1288660I-3937J0D01*
G01X1296534Y526162D02*
Y422182D01*
G01X1288660D02*
G03X1296534I3937J0D01*
G01X1288660Y582874D02*
Y484252D01*
G01Y582874D02*
Y484252D01*
G01X1284723Y480315D02*
G03X1288660Y484252I0J3937D01*
G01X1284723Y480315D02*
G03X1288660Y484252I0J3937D01*
G01Y468504D02*
G03X1284723Y472441I-3937J0D01*
G01X1288660Y468504D02*
G03X1284723Y472441I-3937J0D01*
G01X1296534Y578937D02*
Y551359D01*
G01X1288660D02*
G03X1296534I3937J0D01*
G01Y526162D02*
G03X1288660I-3937J0D01*
G01X1306376Y617126D02*
Y613976D01*
G01Y612126D02*
Y608976D01*
G01Y607126D02*
Y603976D01*
G01Y602126D02*
Y598976D01*
G01Y597126D02*
Y593976D01*
G01Y613976D02*
X1326061D01*
G01Y612126D02*
X1306376D01*
G01Y608976D02*
X1326061D01*
G01Y607126D02*
X1306376D01*
G01Y603976D02*
X1326061D01*
G01Y602126D02*
X1306376D01*
G01Y598976D02*
X1326061D01*
G01Y597126D02*
X1306376D01*
G01Y593976D02*
X1326061D01*
G01X1292597Y586811D02*
X1326061D01*
G01X1292597D02*
X1326061D01*
G01X1292597D02*
G03X1288660Y582874I0J-3937D01*
G01X1292597Y586811D02*
G03X1288660Y582874I0J-3937D01*
G01X1331968Y578937D02*
X1296534D01*
G01X1306376Y652126D02*
Y648976D01*
G01Y647126D02*
Y643976D01*
G01Y642126D02*
Y638976D01*
G01Y637126D02*
Y633976D01*
G01Y632126D02*
Y628976D01*
G01Y627126D02*
Y623976D01*
G01Y622126D02*
Y618976D01*
G01X1301258Y677953D02*
Y660709D01*
G01D02*
X1326061D01*
G01D02*
X1290038D01*
G01X1301258D02*
X1290038D01*
G01X1326061Y657953D02*
X1290038D01*
G01X1326061D02*
X1290038D01*
G01X1326061Y652126D02*
X1306376D01*
G01Y648976D02*
X1326061D01*
G01Y647126D02*
X1306376D01*
G01Y643976D02*
X1326061D01*
G01Y642126D02*
X1306376D01*
G01Y638976D02*
X1326061D01*
G01Y637126D02*
X1306376D01*
G01Y633976D02*
X1326061D01*
G01Y632126D02*
X1306376D01*
G01Y628976D02*
X1326061D01*
G01Y627126D02*
X1306376D01*
G01Y623976D02*
X1326061D01*
G01Y622126D02*
X1306376D01*
G01Y618976D02*
X1326061D01*
G01Y617126D02*
X1306376D01*
G01X1290038Y660709D02*
G03Y657953I0J-1378D01*
G01Y660709D02*
G03Y657953I0J-1378D01*
G01X1301258Y757953D02*
Y720709D01*
G01Y717953D02*
Y680709D01*
G01Y720709D02*
X1326061D01*
G01Y717953D02*
X1301258D01*
G01Y680709D02*
X1326061D01*
G01Y677953D02*
X1301258D01*
G01X1271416Y726378D02*
Y706693D01*
G01X1263542Y730315D02*
X1267479D01*
G01Y702756D02*
X1263542D01*
G01X1271416Y726378D02*
G03X1267479Y730315I-3937J0D01*
G01Y702756D02*
G03X1271416Y706693I0J3937D01*
G01X1301258Y797953D02*
Y760709D01*
G01D02*
X1326061D01*
G01Y757953D02*
X1301258D01*
G01Y837953D02*
Y800709D01*
G01X1326061Y841850D02*
X1292597D01*
G01X1326061D02*
X1292597D01*
G01X1326061Y837953D02*
X1301258D01*
G01Y800709D02*
X1326061D01*
G01Y797953D02*
X1301258D01*
G01X1288660Y845787D02*
G03X1292597Y841850I3937J0D01*
G01X1288660Y845787D02*
G03X1292597Y841850I3937J0D01*
G01X1288660Y948819D02*
Y845787D01*
G01Y948819D02*
Y845787D01*
G01X1296534Y849724D02*
Y877300D01*
G01Y877296D02*
G03X1288660I-3937J0D01*
G01X1296534Y948819D02*
Y902497D01*
G01X1288660D02*
G03X1296534I3937J0D01*
G01X1331968Y849724D02*
X1296534D01*
G01X1288660Y948819D02*
G03X1284723Y952756I-3937J0D01*
G01X1288660Y948819D02*
G03X1284723Y952756I-3937J0D01*
G01X1296534Y948819D02*
G03X1284723Y960630I-11811J0D01*
G01X1331968Y958441D02*
G03X1317968Y972441I-14000J0D01*
G01X1308151Y1400383D02*
Y1381446D01*
G01X1331968Y-5685D02*
Y98622D01*
G01X1331967Y112402D02*
Y171732D01*
G01X1329998Y110433D02*
Y173701D01*
G01Y110433D02*
Y173701D01*
G01X1326061Y113661D02*
Y116811D01*
G01Y118661D02*
Y121811D01*
G01Y123661D02*
Y126811D01*
G01Y128661D02*
Y131811D01*
G01Y133661D02*
Y136811D01*
G01Y138661D02*
Y141811D01*
G01Y143661D02*
Y146811D01*
G01Y148661D02*
Y151811D01*
G01Y153661D02*
Y156811D01*
G01Y158661D02*
Y161811D01*
G01Y106496D02*
X1329998Y110433D01*
G01X1326061Y106496D02*
X1331967Y112402D01*
G01Y186299D02*
Y355630D01*
G01X1329998Y184331D02*
Y357598D01*
G01Y184331D02*
Y357598D01*
G01X1326061Y163661D02*
Y166811D01*
G01Y168661D02*
Y171811D01*
G01Y180394D02*
Y197638D01*
G01Y200394D02*
Y237638D01*
G01Y180394D02*
X1329998Y184331D01*
G01X1326061Y180394D02*
X1331967Y186299D01*
G01Y171732D02*
X1326061Y177638D01*
G01X1329998Y173701D02*
X1326061Y177638D01*
G01Y240394D02*
Y277638D01*
G01Y280394D02*
Y317638D01*
G01Y320394D02*
Y357638D01*
G01X1331967Y355630D02*
X1326061Y361535D01*
G01X1329998Y357598D02*
X1326061Y361535D01*
G01X1331968Y578937D02*
Y369409D01*
G01X1331967Y592717D02*
Y652047D01*
G01X1329998Y590748D02*
Y654016D01*
G01Y590748D02*
Y654016D01*
G01X1326061Y593976D02*
Y597126D01*
G01Y598976D02*
Y602126D01*
G01Y603976D02*
Y607126D01*
G01Y608976D02*
Y612126D01*
G01Y613976D02*
Y617126D01*
G01Y586811D02*
X1329998Y590748D01*
G01X1326061Y586811D02*
X1331967Y592717D01*
G01Y666614D02*
Y835945D01*
G01X1329998Y664646D02*
Y837913D01*
G01Y664646D02*
Y837913D01*
G01X1326061Y618976D02*
Y622126D01*
G01Y623976D02*
Y627126D01*
G01Y628976D02*
Y632126D01*
G01Y633976D02*
Y637126D01*
G01Y638976D02*
Y642126D01*
G01Y643976D02*
Y647126D01*
G01Y648976D02*
Y652126D01*
G01Y660709D02*
Y677953D01*
G01Y660709D02*
X1329998Y664646D01*
G01X1326061Y660709D02*
X1331967Y666614D01*
G01Y652047D02*
X1326061Y657953D01*
G01X1329998Y654016D02*
X1326061Y657953D01*
G01Y680709D02*
Y717953D01*
G01Y720709D02*
Y757953D01*
G01Y760709D02*
Y797953D01*
G01Y800709D02*
Y837953D01*
G01X1331967Y835945D02*
X1326061Y841850D01*
G01X1329998Y837913D02*
X1326061Y841850D01*
G01X1331968Y958441D02*
Y849724D01*
G01Y1000315D02*
Y966315D01*
G01X1332961Y1001181D02*
X1333971Y1001831D01*
X1334549Y1002697D01*
X1334693Y1003671D01*
X1334549Y1004537D01*
X1333827Y1005404D01*
X1332961Y1005945D01*
X1332095Y1006053D01*
X1331084Y1005837D01*
X1330363Y1005079D01*
X1330074Y1004321D01*
Y1003346D01*
G01Y1004321D02*
X1329641Y1004970D01*
X1328919Y1005512D01*
X1328053Y1005728D01*
X1327187Y1005512D01*
X1326465Y1004970D01*
X1326032Y1003996D01*
X1326176Y1003022D01*
X1326754Y1002047D01*
G01X1334693Y1013523D02*
X1326032D01*
X1332239Y1009517D01*
Y1014931D01*
G01X1333683Y1019044D02*
X1334404Y1019802D01*
X1334693Y1020668D01*
X1334404Y1021535D01*
X1333538Y1022292D01*
X1332239Y1022834D01*
X1330940Y1023050D01*
X1329352D01*
X1328053Y1022834D01*
X1326898Y1022292D01*
X1326321Y1021643D01*
X1326032Y1020885D01*
X1326321Y1020019D01*
X1326898Y1019369D01*
X1327764Y1018936D01*
X1328919Y1018720D01*
X1329929Y1018936D01*
X1330940Y1019478D01*
X1331517Y1020127D01*
X1331662Y1020885D01*
X1331373Y1021751D01*
X1330651Y1022401D01*
X1329352Y1023050D01*
G01X1334982Y1029546D02*
X1334837Y1029329D01*
X1334549D01*
X1334404Y1029546D01*
X1334549Y1029763D01*
X1334837D01*
X1334982Y1029546D01*
G01X1332961Y1035825D02*
X1333971Y1036475D01*
X1334549Y1037341D01*
X1334693Y1038315D01*
X1334549Y1039181D01*
X1333827Y1040048D01*
X1332961Y1040589D01*
X1332095Y1040697D01*
X1331084Y1040481D01*
X1330363Y1039723D01*
X1330074Y1038965D01*
Y1037990D01*
G01Y1038965D02*
X1329641Y1039614D01*
X1328919Y1040156D01*
X1328053Y1040372D01*
X1327187Y1040156D01*
X1326465Y1039614D01*
X1326032Y1038640D01*
X1326176Y1037666D01*
X1326754Y1036691D01*
G01X1327475Y1044811D02*
X1326610Y1045461D01*
X1326176Y1046218D01*
X1326032Y1047085D01*
X1326321Y1048167D01*
X1327042Y1048925D01*
X1327908Y1049142D01*
X1328775Y1049033D01*
X1329496Y1048600D01*
X1330940Y1046435D01*
X1331950Y1045461D01*
X1333394Y1044811D01*
X1334693Y1044594D01*
Y1049142D01*
G01X1420049Y-792523D02*
X1421414Y-792263D01*
X1422974Y-791483D01*
X1423949Y-790183D01*
X1424339Y-788363D01*
X1423949Y-786543D01*
X1422779Y-784983D01*
X1421024Y-784203D01*
X1419074D01*
X1417904Y-783683D01*
X1416929Y-782383D01*
X1416539Y-780563D01*
X1417124Y-778743D01*
X1418489Y-777443D01*
X1420049Y-776923D01*
X1421609Y-777443D01*
X1422974Y-778743D01*
X1423559Y-780563D01*
X1423169Y-782383D01*
X1422194Y-783683D01*
X1421024Y-784203D01*
X1419074D01*
X1417319Y-784983D01*
X1416149Y-786543D01*
X1415759Y-788363D01*
X1416149Y-790183D01*
X1417124Y-791483D01*
X1418684Y-792263D01*
X1420049Y-792523D01*
G01Y1385233D02*
X1421414Y1385493D01*
X1422974Y1386273D01*
X1423949Y1387573D01*
X1424339Y1389393D01*
X1423949Y1391213D01*
X1422779Y1392773D01*
X1421024Y1393553D01*
X1419074D01*
X1417904Y1394073D01*
X1416929Y1395373D01*
X1416539Y1397193D01*
X1417124Y1399013D01*
X1418489Y1400313D01*
X1420049Y1400833D01*
X1421609Y1400313D01*
X1422974Y1399013D01*
X1423559Y1397193D01*
X1423169Y1395373D01*
X1422194Y1394073D01*
X1421024Y1393553D01*
X1419074D01*
X1417319Y1392773D01*
X1416149Y1391213D01*
X1415759Y1389393D01*
X1416149Y1387573D01*
X1417124Y1386273D01*
X1418684Y1385493D01*
X1420049Y1385233D01*
G01X1527821Y-777373D02*
Y-796310D01*
G01Y1400383D02*
Y1381446D01*
G01X1636404Y-790703D02*
X1637769Y-792003D01*
X1639329Y-792523D01*
X1640889Y-792003D01*
X1642254Y-790443D01*
X1643229Y-788103D01*
X1643619Y-785763D01*
Y-782903D01*
X1643229Y-780563D01*
X1642254Y-778483D01*
X1641084Y-777443D01*
X1639719Y-776923D01*
X1638159Y-777443D01*
X1636989Y-778483D01*
X1636209Y-780043D01*
X1635819Y-782123D01*
X1636209Y-783943D01*
X1637184Y-785763D01*
X1638354Y-786803D01*
X1639719Y-787063D01*
X1641279Y-786543D01*
X1642449Y-785243D01*
X1643619Y-782903D01*
G01X1636404Y1387053D02*
X1637769Y1385753D01*
X1639329Y1385233D01*
X1640889Y1385753D01*
X1642254Y1387313D01*
X1643229Y1389653D01*
X1643619Y1391993D01*
Y1394853D01*
X1643229Y1397193D01*
X1642254Y1399273D01*
X1641084Y1400313D01*
X1639719Y1400833D01*
X1638159Y1400313D01*
X1636989Y1399273D01*
X1636209Y1397713D01*
X1635819Y1395633D01*
X1636209Y1393813D01*
X1637184Y1391993D01*
X1638354Y1390953D01*
X1639719Y1390693D01*
X1641279Y1391213D01*
X1642449Y1392513D01*
X1643619Y1394853D01*
G01X1747491Y-777373D02*
Y-796310D01*
G01Y1400383D02*
Y1381446D01*
G01X1811321Y-777373D02*
X2201084D01*
G01X1856736Y-792523D02*
Y-776923D01*
X1854396Y-780043D01*
G01Y-792523D02*
X1859076D01*
G01X1874636Y-776923D02*
X1873076Y-777443D01*
X1871906Y-778743D01*
X1871126Y-780303D01*
X1870541Y-782383D01*
X1870346Y-784723D01*
X1870541Y-787063D01*
X1871126Y-789143D01*
X1871906Y-790703D01*
X1873076Y-792003D01*
X1874636Y-792523D01*
X1876196Y-792003D01*
X1877366Y-790703D01*
X1878146Y-789143D01*
X1878731Y-787063D01*
X1878926Y-784723D01*
X1878731Y-782383D01*
X1878146Y-780303D01*
X1877366Y-778743D01*
X1876196Y-777443D01*
X1874636Y-776923D01*
G01X1856736Y1385233D02*
Y1400833D01*
X1854396Y1397713D01*
G01Y1385233D02*
X1859076D01*
G01X1874636Y1400833D02*
X1873076Y1400313D01*
X1871906Y1399013D01*
X1871126Y1397453D01*
X1870541Y1395373D01*
X1870346Y1393033D01*
X1870541Y1390693D01*
X1871126Y1388613D01*
X1871906Y1387053D01*
X1873076Y1385753D01*
X1874636Y1385233D01*
X1876196Y1385753D01*
X1877366Y1387053D01*
X1878146Y1388613D01*
X1878731Y1390693D01*
X1878926Y1393033D01*
X1878731Y1395373D01*
X1878146Y1397453D01*
X1877366Y1399013D01*
X1876196Y1400313D01*
X1874636Y1400833D01*
G01X1967160Y-777373D02*
Y-796310D01*
G01Y1400383D02*
Y1381446D01*
G01X2032337Y-693460D02*
Y-753628D01*
G01D02*
X2784437D01*
G01X2032337Y-693460D02*
Y-648334D01*
G01X2822042Y-693460D02*
X2032337D01*
G01Y-648334D02*
Y-603208D01*
G01Y-648334D02*
X2408387D01*
G01X2045423Y-615487D02*
X2051673Y-635487D01*
X2057923Y-615487D01*
G01X2067923Y-626487D02*
X2075923D01*
X2075173Y-624154D01*
X2073923Y-622821D01*
X2072173Y-622154D01*
X2070423Y-622487D01*
X2068923Y-623487D01*
X2067923Y-625821D01*
X2067423Y-627821D01*
Y-629820D01*
X2067923Y-631821D01*
X2069173Y-633821D01*
X2070673Y-635154D01*
X2072423Y-635487D01*
X2074173Y-634820D01*
X2075923Y-632821D01*
G01X2088173Y-635487D02*
Y-622154D01*
G01Y-624820D02*
X2089423Y-623487D01*
X2090673Y-622487D01*
X2092423Y-622154D01*
X2093673Y-622487D01*
X2095173Y-623487D01*
G01X2107923Y-633154D02*
X2109173Y-634487D01*
X2110923Y-635487D01*
X2112423D01*
X2113923Y-634820D01*
X2114923Y-633821D01*
X2115423Y-632488D01*
X2115173Y-630487D01*
X2114173Y-629487D01*
X2109673Y-627487D01*
X2108673Y-625153D01*
X2109173Y-623487D01*
X2110173Y-622487D01*
X2111673Y-622154D01*
X2113173Y-622487D01*
X2114673Y-623487D01*
G01X2131673Y-622154D02*
Y-635487D01*
G01Y-616821D02*
X2131173Y-616487D01*
Y-615820D01*
X2131673Y-615487D01*
X2132173Y-615820D01*
Y-616487D01*
X2131673Y-616821D01*
G01X2151673Y-635487D02*
X2150173Y-635154D01*
X2148673Y-633821D01*
X2147673Y-631487D01*
X2147173Y-628821D01*
X2147673Y-626154D01*
X2148673Y-623820D01*
X2150173Y-622487D01*
X2151673Y-622154D01*
X2153173Y-622487D01*
X2154673Y-623820D01*
X2155673Y-626154D01*
X2155923Y-628821D01*
X2155673Y-631487D01*
X2154673Y-633821D01*
X2153173Y-635154D01*
X2151673Y-635487D01*
G01X2167423D02*
Y-622154D01*
G01Y-625487D02*
X2168423Y-623820D01*
X2169923Y-622487D01*
X2171923Y-622154D01*
X2173673Y-622487D01*
X2175173Y-623820D01*
X2175923Y-626154D01*
Y-635487D01*
G01X2059875Y-666062D02*
X2058375Y-665062D01*
X2056625Y-664395D01*
X2054625D01*
X2052375Y-665395D01*
X2050625Y-667062D01*
X2049375Y-669062D01*
X2048375Y-672395D01*
X2048125Y-675395D01*
X2048625Y-678395D01*
X2049375Y-680395D01*
X2050875Y-682395D01*
X2052625Y-683728D01*
X2054375Y-684395D01*
X2056125D01*
X2057875Y-683728D01*
X2059375Y-682729D01*
X2060625Y-681396D01*
G01X2070875Y-684395D02*
Y-671062D01*
G01Y-673728D02*
X2072125Y-672395D01*
X2073375Y-671395D01*
X2075125Y-671062D01*
X2076375Y-671395D01*
X2077875Y-672395D01*
G01X2090625Y-675395D02*
X2098625D01*
X2097875Y-673062D01*
X2096625Y-671729D01*
X2094875Y-671062D01*
X2093125Y-671395D01*
X2091625Y-672395D01*
X2090625Y-674729D01*
X2090125Y-676729D01*
Y-678728D01*
X2090625Y-680729D01*
X2091875Y-682729D01*
X2093375Y-684062D01*
X2095125Y-684395D01*
X2096875Y-683728D01*
X2098625Y-681729D01*
G01X2118875Y-684395D02*
Y-671062D01*
G01Y-673395D02*
X2117875Y-672062D01*
X2116375Y-671395D01*
X2114625Y-671062D01*
X2112875Y-671729D01*
X2111375Y-673062D01*
X2110375Y-675062D01*
X2109875Y-677729D01*
X2110375Y-680395D01*
X2111375Y-682395D01*
X2112875Y-683728D01*
X2114625Y-684395D01*
X2116375Y-684062D01*
X2117875Y-683062D01*
X2118875Y-681729D01*
G01X2134375Y-664395D02*
Y-684395D01*
G01X2130875Y-671062D02*
X2137875D01*
G01X2150625Y-675395D02*
X2158625D01*
X2157875Y-673062D01*
X2156625Y-671729D01*
X2154875Y-671062D01*
X2153125Y-671395D01*
X2151625Y-672395D01*
X2150625Y-674729D01*
X2150125Y-676729D01*
Y-678728D01*
X2150625Y-680729D01*
X2151875Y-682729D01*
X2153375Y-684062D01*
X2155125Y-684395D01*
X2156875Y-683728D01*
X2158625Y-681729D01*
G01X2178875Y-664395D02*
Y-684395D01*
G01Y-681396D02*
X2177875Y-683062D01*
X2176375Y-684062D01*
X2174625Y-684395D01*
X2172625Y-683728D01*
X2171125Y-682062D01*
X2170125Y-680062D01*
X2169875Y-677729D01*
X2170125Y-675395D01*
X2171125Y-673395D01*
X2172625Y-671729D01*
X2174625Y-671062D01*
X2176375Y-671395D01*
X2177625Y-672062D01*
X2178875Y-673395D01*
G01X2032337Y-603208D02*
Y-497938D01*
G01Y-603208D02*
X2822042D01*
G01X2049375Y-591473D02*
Y-571473D01*
X2055375D01*
X2057375Y-572473D01*
X2058875Y-574806D01*
X2059375Y-577473D01*
X2058875Y-580140D01*
X2057625Y-582140D01*
X2055375Y-583140D01*
X2049375D01*
G01X2079875Y-573140D02*
X2078375Y-572140D01*
X2076625Y-571473D01*
X2074625D01*
X2072375Y-572473D01*
X2070625Y-574140D01*
X2069375Y-576140D01*
X2068375Y-579473D01*
X2068125Y-582473D01*
X2068625Y-585473D01*
X2069375Y-587473D01*
X2070875Y-589473D01*
X2072625Y-590806D01*
X2074375Y-591473D01*
X2076125D01*
X2077875Y-590806D01*
X2079375Y-589807D01*
X2080625Y-588474D01*
G01X2096375Y-580806D02*
X2097375Y-579806D01*
X2098125Y-578140D01*
X2098625Y-575806D01*
X2098125Y-573806D01*
X2097125Y-572473D01*
X2095375Y-571473D01*
X2088625D01*
Y-591473D01*
X2096875D01*
X2098625Y-590140D01*
X2099625Y-588140D01*
X2100125Y-585806D01*
X2099625Y-583473D01*
X2098125Y-581473D01*
X2096375Y-580806D01*
X2088625D01*
G01X2128625Y-591473D02*
Y-571473D01*
X2140125Y-591473D01*
Y-571473D01*
G01X2154375Y-591473D02*
X2152875Y-591140D01*
X2151375Y-589807D01*
X2150375Y-587473D01*
X2149875Y-584807D01*
X2150375Y-582140D01*
X2151375Y-579806D01*
X2152875Y-578473D01*
X2154375Y-578140D01*
X2155875Y-578473D01*
X2157375Y-579806D01*
X2158375Y-582140D01*
X2158625Y-584807D01*
X2158375Y-587473D01*
X2157375Y-589807D01*
X2155875Y-591140D01*
X2154375Y-591473D01*
G01X2174375Y-592140D02*
X2173875Y-591806D01*
Y-591140D01*
X2174375Y-590806D01*
X2174875Y-591140D01*
Y-591806D01*
X2174375Y-592140D01*
G01X2032337Y-558082D02*
X2822042D01*
G01X2057820Y-547260D02*
Y-522260D01*
X2066010Y-543093D01*
X2074200Y-522260D01*
Y-547260D01*
G01X2091210D02*
X2089320Y-546843D01*
X2087430Y-545177D01*
X2086170Y-542260D01*
X2085540Y-538927D01*
X2086170Y-535594D01*
X2087430Y-532677D01*
X2089320Y-531010D01*
X2091210Y-530594D01*
X2093100Y-531010D01*
X2094990Y-532677D01*
X2096250Y-535594D01*
X2096565Y-538927D01*
X2096250Y-542260D01*
X2094990Y-545177D01*
X2093100Y-546843D01*
X2091210Y-547260D01*
G01X2122080Y-522260D02*
Y-547260D01*
G01Y-543511D02*
X2120820Y-545594D01*
X2118930Y-546843D01*
X2116725Y-547260D01*
X2114205Y-546427D01*
X2112315Y-544344D01*
X2111055Y-541844D01*
X2110740Y-538927D01*
X2111055Y-536010D01*
X2112315Y-533510D01*
X2114205Y-531427D01*
X2116725Y-530594D01*
X2118930Y-531010D01*
X2120505Y-531844D01*
X2122080Y-533510D01*
G01X2136885Y-536010D02*
X2146965D01*
X2146020Y-533093D01*
X2144445Y-531427D01*
X2142240Y-530594D01*
X2140035Y-531010D01*
X2138145Y-532260D01*
X2136885Y-535177D01*
X2136255Y-537677D01*
Y-540177D01*
X2136885Y-542677D01*
X2138460Y-545177D01*
X2140350Y-546843D01*
X2142555Y-547260D01*
X2144760Y-546427D01*
X2146965Y-543927D01*
G01X2166810Y-547260D02*
Y-522260D01*
G01X2032337Y-497938D02*
X2822042D01*
G01X2012936Y1381446D02*
X2520810D01*
G01X2077163Y-792523D02*
Y-776923D01*
X2074823Y-780043D01*
G01Y-792523D02*
X2079503D01*
G01X2095063D02*
Y-776923D01*
X2092723Y-780043D01*
G01Y-792523D02*
X2097403D01*
G01X2113698Y-717898D02*
X2118108Y-742898D01*
X2123148Y-717898D01*
X2128188Y-742898D01*
X2132598Y-717898D01*
G01X2148348Y-726232D02*
Y-742898D01*
G01Y-719565D02*
X2147718Y-719148D01*
Y-718315D01*
X2148348Y-717898D01*
X2148978Y-718315D01*
Y-719148D01*
X2148348Y-719565D01*
G01X2168823Y-739982D02*
X2170398Y-741648D01*
X2172603Y-742898D01*
X2174493D01*
X2176383Y-742065D01*
X2177643Y-740815D01*
X2178273Y-739149D01*
X2177958Y-736648D01*
X2176698Y-735398D01*
X2171028Y-732899D01*
X2169768Y-729981D01*
X2170398Y-727898D01*
X2171658Y-726648D01*
X2173548Y-726232D01*
X2175438Y-726648D01*
X2177328Y-727898D01*
G01X2198748Y-717898D02*
Y-742898D01*
G01X2194338Y-726232D02*
X2203158D01*
G01X2219538Y-742898D02*
Y-726232D01*
G01Y-729564D02*
X2221113Y-727898D01*
X2222688Y-726648D01*
X2224893Y-726232D01*
X2226468Y-726648D01*
X2228358Y-727898D01*
G01X2249148Y-742898D02*
X2247258Y-742481D01*
X2245368Y-740815D01*
X2244108Y-737898D01*
X2243478Y-734565D01*
X2244108Y-731232D01*
X2245368Y-728315D01*
X2247258Y-726648D01*
X2249148Y-726232D01*
X2251038Y-726648D01*
X2252928Y-728315D01*
X2254188Y-731232D01*
X2254503Y-734565D01*
X2254188Y-737898D01*
X2252928Y-740815D01*
X2251038Y-742481D01*
X2249148Y-742898D01*
G01X2268993D02*
Y-726232D01*
G01Y-730398D02*
X2270253Y-728315D01*
X2272143Y-726648D01*
X2274663Y-726232D01*
X2276868Y-726648D01*
X2278758Y-728315D01*
X2279703Y-731232D01*
Y-742898D01*
G01X2331678Y-719982D02*
X2329788Y-718731D01*
X2327583Y-717898D01*
X2325063D01*
X2322228Y-719148D01*
X2320023Y-721231D01*
X2318448Y-723732D01*
X2317188Y-727898D01*
X2316873Y-731648D01*
X2317503Y-735398D01*
X2318448Y-737898D01*
X2320338Y-740399D01*
X2322543Y-742065D01*
X2324748Y-742898D01*
X2326953D01*
X2329158Y-742065D01*
X2331048Y-740815D01*
X2332623Y-739149D01*
G01X2349948Y-742898D02*
X2348058Y-742481D01*
X2346168Y-740815D01*
X2344908Y-737898D01*
X2344278Y-734565D01*
X2344908Y-731232D01*
X2346168Y-728315D01*
X2348058Y-726648D01*
X2349948Y-726232D01*
X2351838Y-726648D01*
X2353728Y-728315D01*
X2354988Y-731232D01*
X2355303Y-734565D01*
X2354988Y-737898D01*
X2353728Y-740815D01*
X2351838Y-742481D01*
X2349948Y-742898D01*
G01X2370738D02*
Y-726232D01*
G01Y-729564D02*
X2372313Y-727898D01*
X2373888Y-726648D01*
X2376093Y-726232D01*
X2377668Y-726648D01*
X2379558Y-727898D01*
G01X2394678Y-751231D02*
Y-726232D01*
G01Y-729981D02*
X2396253Y-727898D01*
X2397828Y-726648D01*
X2400348Y-726232D01*
X2402553Y-726648D01*
X2404758Y-728731D01*
X2405703Y-731648D01*
X2406018Y-734565D01*
X2405703Y-737482D01*
X2404758Y-740399D01*
X2402868Y-742065D01*
X2400348Y-742898D01*
X2398143Y-742481D01*
X2395938Y-741232D01*
X2394678Y-739565D01*
G01X2425548Y-742898D02*
X2423658Y-742481D01*
X2421768Y-740815D01*
X2420508Y-737898D01*
X2419878Y-734565D01*
X2420508Y-731232D01*
X2421768Y-728315D01*
X2423658Y-726648D01*
X2425548Y-726232D01*
X2427438Y-726648D01*
X2429328Y-728315D01*
X2430588Y-731232D01*
X2430903Y-734565D01*
X2430588Y-737898D01*
X2429328Y-740815D01*
X2427438Y-742481D01*
X2425548Y-742898D01*
G01X2446338D02*
Y-726232D01*
G01Y-729564D02*
X2447913Y-727898D01*
X2449488Y-726648D01*
X2451693Y-726232D01*
X2453268Y-726648D01*
X2455158Y-727898D01*
G01X2481618Y-742898D02*
Y-726232D01*
G01Y-729148D02*
X2480358Y-727482D01*
X2478468Y-726648D01*
X2476263Y-726232D01*
X2474058Y-727065D01*
X2472168Y-728731D01*
X2470908Y-731232D01*
X2470278Y-734565D01*
X2470908Y-737898D01*
X2472168Y-740399D01*
X2474058Y-742065D01*
X2476263Y-742898D01*
X2478468Y-742481D01*
X2480358Y-741232D01*
X2481618Y-739565D01*
G01X2501148Y-717898D02*
Y-742898D01*
G01X2496738Y-726232D02*
X2505558D01*
G01X2526348D02*
Y-742898D01*
G01Y-719565D02*
X2525718Y-719148D01*
Y-718315D01*
X2526348Y-717898D01*
X2526978Y-718315D01*
Y-719148D01*
X2526348Y-719565D01*
G01X2551548Y-742898D02*
X2549658Y-742481D01*
X2547768Y-740815D01*
X2546508Y-737898D01*
X2545878Y-734565D01*
X2546508Y-731232D01*
X2547768Y-728315D01*
X2549658Y-726648D01*
X2551548Y-726232D01*
X2553438Y-726648D01*
X2555328Y-728315D01*
X2556588Y-731232D01*
X2556903Y-734565D01*
X2556588Y-737898D01*
X2555328Y-740815D01*
X2553438Y-742481D01*
X2551548Y-742898D01*
G01X2571393D02*
Y-726232D01*
G01Y-730398D02*
X2572653Y-728315D01*
X2574543Y-726648D01*
X2577063Y-726232D01*
X2579268Y-726648D01*
X2581158Y-728315D01*
X2582103Y-731232D01*
Y-742898D01*
G01X2077163Y1385233D02*
Y1400833D01*
X2074823Y1397713D01*
G01Y1385233D02*
X2079503D01*
G01X2095063D02*
Y1400833D01*
X2092723Y1397713D01*
G01Y1385233D02*
X2097403D01*
G01X2185882Y-777373D02*
Y-796310D01*
G01X2201084Y-777373D02*
X2851519D01*
G01X2220362Y-693460D02*
Y-497938D01*
G01X2186828Y1400383D02*
Y1381446D01*
G01X2294938Y-792523D02*
Y-776923D01*
X2292598Y-780043D01*
G01Y-792523D02*
X2297278D01*
G01X2309133Y-779523D02*
X2310303Y-777963D01*
X2311668Y-777183D01*
X2313228Y-776923D01*
X2315178Y-777443D01*
X2316543Y-778743D01*
X2316933Y-780303D01*
X2316738Y-781863D01*
X2315958Y-783163D01*
X2312058Y-785763D01*
X2310303Y-787583D01*
X2309133Y-790183D01*
X2308743Y-792523D01*
X2316933D01*
G01X2244739Y-640125D02*
Y-620125D01*
X2241739Y-624125D01*
G01Y-640125D02*
X2247739D01*
G01X2242915Y-593064D02*
Y-573064D01*
X2239915Y-577064D01*
G01Y-593064D02*
X2245915D01*
G01X2258165Y-576397D02*
X2259665Y-574398D01*
X2261415Y-573397D01*
X2263415Y-573064D01*
X2265915Y-573731D01*
X2267665Y-575397D01*
X2268165Y-577397D01*
X2267915Y-579398D01*
X2266915Y-581064D01*
X2261915Y-584397D01*
X2259665Y-586731D01*
X2258165Y-590065D01*
X2257665Y-593064D01*
X2268165D01*
G01X2277415Y-590065D02*
X2278915Y-591731D01*
X2280665Y-592731D01*
X2282915Y-593064D01*
X2285165Y-592397D01*
X2286915Y-591064D01*
X2288165Y-588731D01*
X2288415Y-586064D01*
X2287915Y-583398D01*
X2286665Y-581731D01*
X2284915Y-580398D01*
X2283165Y-580064D01*
X2281415Y-580398D01*
X2279165Y-581731D01*
X2279915Y-573064D01*
X2286665D01*
G01X2298165Y-576397D02*
X2299665Y-574398D01*
X2301415Y-573397D01*
X2303415Y-573064D01*
X2305915Y-573731D01*
X2307665Y-575397D01*
X2308165Y-577397D01*
X2307915Y-579398D01*
X2306915Y-581064D01*
X2301915Y-584397D01*
X2299665Y-586731D01*
X2298165Y-590065D01*
X2297665Y-593064D01*
X2308165D01*
G01X2317415Y-589064D02*
X2318915Y-591398D01*
X2320915Y-592731D01*
X2323165Y-593064D01*
X2325165Y-592731D01*
X2327165Y-591064D01*
X2328415Y-589064D01*
X2328665Y-587064D01*
X2328165Y-584731D01*
X2326415Y-583064D01*
X2324665Y-582397D01*
X2322415D01*
G01X2324665D02*
X2326165Y-581397D01*
X2327415Y-579731D01*
X2327915Y-577731D01*
X2327415Y-575731D01*
X2326165Y-574064D01*
X2323915Y-573064D01*
X2321665Y-573397D01*
X2319415Y-574731D01*
G01X2243946Y-539512D02*
Y-519512D01*
G01X2253446D02*
X2243946Y-531846D01*
G01X2254946Y-539512D02*
X2248196Y-526179D01*
G01X2263696Y-539512D02*
Y-519512D01*
X2275196Y-539512D01*
Y-519512D01*
G01X2289446Y-539512D02*
X2287446Y-539179D01*
X2285696Y-537846D01*
X2284196Y-535846D01*
X2283196Y-533512D01*
X2282696Y-530845D01*
Y-528179D01*
X2283196Y-525512D01*
X2284196Y-523178D01*
X2285696Y-521179D01*
X2287446Y-519845D01*
X2289446Y-519512D01*
X2291446Y-519845D01*
X2293196Y-521179D01*
X2294696Y-523178D01*
X2295696Y-525512D01*
X2296196Y-528179D01*
Y-530845D01*
X2295696Y-533512D01*
X2294696Y-535846D01*
X2293196Y-537846D01*
X2291446Y-539179D01*
X2289446Y-539512D01*
G01X2304196D02*
X2314696Y-519512D01*
G01X2304196D02*
X2314696Y-539512D01*
G01X2344446D02*
Y-519512D01*
X2350446D01*
X2352446Y-520512D01*
X2353946Y-522845D01*
X2354446Y-525512D01*
X2353946Y-528179D01*
X2352696Y-530179D01*
X2350446Y-531179D01*
X2344446D01*
G01X2369446Y-539512D02*
X2367446Y-539179D01*
X2365696Y-537846D01*
X2364196Y-535846D01*
X2363196Y-533512D01*
X2362696Y-530845D01*
Y-528179D01*
X2363196Y-525512D01*
X2364196Y-523178D01*
X2365696Y-521179D01*
X2367446Y-519845D01*
X2369446Y-519512D01*
X2371446Y-519845D01*
X2373196Y-521179D01*
X2374696Y-523178D01*
X2375696Y-525512D01*
X2376196Y-528179D01*
Y-530845D01*
X2375696Y-533512D01*
X2374696Y-535846D01*
X2373196Y-537846D01*
X2371446Y-539179D01*
X2369446Y-539512D01*
G01X2381946Y-519512D02*
X2385446Y-539512D01*
X2389446Y-519512D01*
X2393446Y-539512D01*
X2396946Y-519512D01*
G01X2414446Y-539512D02*
X2404446D01*
Y-519512D01*
X2414446D01*
G01X2410446Y-529178D02*
X2404446D01*
G01X2424446Y-539512D02*
Y-519512D01*
X2430696D01*
X2432696Y-520512D01*
X2433946Y-521845D01*
X2434446Y-524512D01*
X2433946Y-527179D01*
X2432446Y-528845D01*
X2430696Y-529846D01*
X2424446D01*
G01X2430696D02*
X2434446Y-539512D01*
G01X2469446Y-519512D02*
Y-539512D01*
G01X2463696Y-519512D02*
X2475196D01*
G01X2484446Y-539512D02*
Y-519512D01*
X2490696D01*
X2492696Y-520512D01*
X2493946Y-521845D01*
X2494446Y-524512D01*
X2493946Y-527179D01*
X2492446Y-528845D01*
X2490696Y-529846D01*
X2484446D01*
G01X2490696D02*
X2494446Y-539512D01*
G01X2503196D02*
X2509446Y-519512D01*
X2515696Y-539512D01*
G01X2513446Y-532512D02*
X2505446D01*
G01X2523696Y-539512D02*
Y-519512D01*
X2535196Y-539512D01*
Y-519512D01*
G01X2544196Y-536846D02*
X2546196Y-538512D01*
X2548446Y-539512D01*
X2550446D01*
X2552446Y-538512D01*
X2553946Y-536846D01*
X2554696Y-534512D01*
X2554196Y-532179D01*
X2552946Y-530179D01*
X2550696Y-528845D01*
X2547696Y-528179D01*
X2545946Y-526846D01*
X2545196Y-524512D01*
X2545696Y-522179D01*
X2546946Y-520512D01*
X2548696Y-519512D01*
X2550446D01*
X2552196Y-520179D01*
X2553696Y-521845D01*
G01X2566446Y-519512D02*
X2572446D01*
G01X2569446D02*
Y-539512D01*
G01X2566446D02*
X2572446D01*
G01X2589446Y-519512D02*
Y-539512D01*
G01X2583696Y-519512D02*
X2595196D01*
G01X2606446D02*
X2612446D01*
G01X2609446D02*
Y-539512D01*
G01X2606446D02*
X2612446D01*
G01X2629446D02*
X2627446Y-539179D01*
X2625696Y-537846D01*
X2624196Y-535846D01*
X2623196Y-533512D01*
X2622696Y-530845D01*
Y-528179D01*
X2623196Y-525512D01*
X2624196Y-523178D01*
X2625696Y-521179D01*
X2627446Y-519845D01*
X2629446Y-519512D01*
X2631446Y-519845D01*
X2633196Y-521179D01*
X2634696Y-523178D01*
X2635696Y-525512D01*
X2636196Y-528179D01*
Y-530845D01*
X2635696Y-533512D01*
X2634696Y-535846D01*
X2633196Y-537846D01*
X2631446Y-539179D01*
X2629446Y-539512D01*
G01X2643696D02*
Y-519512D01*
X2655196Y-539512D01*
Y-519512D01*
G01X2691446Y-528845D02*
X2692446Y-527845D01*
X2693196Y-526179D01*
X2693696Y-523845D01*
X2693196Y-521845D01*
X2692196Y-520512D01*
X2690446Y-519512D01*
X2683696D01*
Y-539512D01*
X2691946D01*
X2693696Y-538179D01*
X2694696Y-536179D01*
X2695196Y-533845D01*
X2694696Y-531512D01*
X2693196Y-529512D01*
X2691446Y-528845D01*
X2683696D01*
G01X2709446Y-539512D02*
X2707446Y-539179D01*
X2705696Y-537846D01*
X2704196Y-535846D01*
X2703196Y-533512D01*
X2702696Y-530845D01*
Y-528179D01*
X2703196Y-525512D01*
X2704196Y-523178D01*
X2705696Y-521179D01*
X2707446Y-519845D01*
X2709446Y-519512D01*
X2711446Y-519845D01*
X2713196Y-521179D01*
X2714696Y-523178D01*
X2715696Y-525512D01*
X2716196Y-528179D01*
Y-530845D01*
X2715696Y-533512D01*
X2714696Y-535846D01*
X2713196Y-537846D01*
X2711446Y-539179D01*
X2709446Y-539512D01*
G01X2723196D02*
X2729446Y-519512D01*
X2735696Y-539512D01*
G01X2733446Y-532512D02*
X2725446D01*
G01X2744446Y-539512D02*
Y-519512D01*
X2750696D01*
X2752696Y-520512D01*
X2753946Y-521845D01*
X2754446Y-524512D01*
X2753946Y-527179D01*
X2752446Y-528845D01*
X2750696Y-529846D01*
X2744446D01*
G01X2750696D02*
X2754446Y-539512D01*
G01X2763946D02*
Y-519512D01*
X2768946D01*
X2770946Y-520512D01*
X2772446Y-521845D01*
X2773696Y-523845D01*
X2774696Y-526179D01*
X2774946Y-529512D01*
X2774696Y-532846D01*
X2773696Y-535179D01*
X2772446Y-537179D01*
X2770946Y-538512D01*
X2768946Y-539512D01*
X2763946D01*
G01X2265317Y1385233D02*
Y1400833D01*
X2262977Y1397713D01*
G01Y1385233D02*
X2267657D01*
G01X2279512Y1398233D02*
X2280682Y1399793D01*
X2282047Y1400573D01*
X2283607Y1400833D01*
X2285557Y1400313D01*
X2286922Y1399013D01*
X2287312Y1397453D01*
X2287117Y1395893D01*
X2286337Y1394593D01*
X2282437Y1391993D01*
X2280682Y1390173D01*
X2279512Y1387573D01*
X2279122Y1385233D01*
X2287312D01*
G01X2376878Y1400383D02*
Y1381446D01*
G01X2406499Y-777373D02*
Y-796310D01*
G01X2409487Y-603015D02*
Y-693145D01*
G01X2408387Y-648334D02*
X2822042D01*
G01X2462506Y-684395D02*
Y-664395D01*
X2467506D01*
X2469506Y-665395D01*
X2471006Y-666728D01*
X2472256Y-668728D01*
X2473256Y-671062D01*
X2473506Y-674395D01*
X2473256Y-677729D01*
X2472256Y-680062D01*
X2471006Y-682062D01*
X2469506Y-683395D01*
X2467506Y-684395D01*
X2462506D01*
G01X2492506D02*
Y-671062D01*
G01Y-673395D02*
X2491506Y-672062D01*
X2490006Y-671395D01*
X2488256Y-671062D01*
X2486506Y-671729D01*
X2485006Y-673062D01*
X2484006Y-675062D01*
X2483506Y-677729D01*
X2484006Y-680395D01*
X2485006Y-682395D01*
X2486506Y-683728D01*
X2488256Y-684395D01*
X2490006Y-684062D01*
X2491506Y-683062D01*
X2492506Y-681729D01*
G01X2508006Y-664395D02*
Y-684395D01*
G01X2504506Y-671062D02*
X2511506D01*
G01X2524256Y-675395D02*
X2532256D01*
X2531506Y-673062D01*
X2530256Y-671729D01*
X2528506Y-671062D01*
X2526756Y-671395D01*
X2525256Y-672395D01*
X2524256Y-674729D01*
X2523756Y-676729D01*
Y-678728D01*
X2524256Y-680729D01*
X2525506Y-682729D01*
X2527006Y-684062D01*
X2528756Y-684395D01*
X2530506Y-683728D01*
X2532256Y-681729D01*
G01X2425433Y-615687D02*
Y-635687D01*
G01X2419683Y-615687D02*
X2431183D01*
G01X2441183Y-635687D02*
Y-615687D01*
G01Y-625353D02*
X2442433Y-623687D01*
X2443683Y-622687D01*
X2445683Y-622354D01*
X2447183Y-622687D01*
X2448933Y-624020D01*
X2449683Y-626021D01*
Y-635687D01*
G01X2465433Y-622354D02*
Y-635687D01*
G01Y-617021D02*
X2464933Y-616687D01*
Y-616020D01*
X2465433Y-615687D01*
X2465933Y-616020D01*
Y-616687D01*
X2465433Y-617021D01*
G01X2489433Y-624020D02*
X2487683Y-622687D01*
X2486183Y-622354D01*
X2484183Y-623021D01*
X2482683Y-624354D01*
X2481683Y-626687D01*
X2481433Y-629021D01*
X2481683Y-631354D01*
X2482683Y-633354D01*
X2484183Y-635020D01*
X2486183Y-635687D01*
X2487933Y-635020D01*
X2489433Y-633687D01*
G01X2501183Y-635687D02*
Y-615687D01*
G01X2509183Y-622354D02*
X2501183Y-630020D01*
G01X2504433Y-627020D02*
X2509683Y-635687D01*
G01X2521183D02*
Y-622354D01*
G01Y-625687D02*
X2522183Y-624020D01*
X2523683Y-622687D01*
X2525683Y-622354D01*
X2527433Y-622687D01*
X2528933Y-624020D01*
X2529683Y-626354D01*
Y-635687D01*
G01X2541683Y-626687D02*
X2549683D01*
X2548933Y-624354D01*
X2547683Y-623021D01*
X2545933Y-622354D01*
X2544183Y-622687D01*
X2542683Y-623687D01*
X2541683Y-626021D01*
X2541183Y-628021D01*
Y-630020D01*
X2541683Y-632021D01*
X2542933Y-634021D01*
X2544433Y-635354D01*
X2546183Y-635687D01*
X2547933Y-635020D01*
X2549683Y-633021D01*
G01X2561683Y-633354D02*
X2562933Y-634687D01*
X2564683Y-635687D01*
X2566183D01*
X2567683Y-635020D01*
X2568683Y-634021D01*
X2569183Y-632688D01*
X2568933Y-630687D01*
X2567933Y-629687D01*
X2563433Y-627687D01*
X2562433Y-625353D01*
X2562933Y-623687D01*
X2563933Y-622687D01*
X2565433Y-622354D01*
X2566933Y-622687D01*
X2568433Y-623687D01*
G01X2581683Y-633354D02*
X2582933Y-634687D01*
X2584683Y-635687D01*
X2586183D01*
X2587683Y-635020D01*
X2588683Y-634021D01*
X2589183Y-632688D01*
X2588933Y-630687D01*
X2587933Y-629687D01*
X2583433Y-627687D01*
X2582433Y-625353D01*
X2582933Y-623687D01*
X2583933Y-622687D01*
X2585433Y-622354D01*
X2586933Y-622687D01*
X2588433Y-623687D01*
G01X2514608Y-792523D02*
Y-776923D01*
X2512268Y-780043D01*
G01Y-792523D02*
X2516948D01*
G01X2528218Y-789403D02*
X2529388Y-791223D01*
X2530948Y-792263D01*
X2532703Y-792523D01*
X2534263Y-792263D01*
X2535823Y-790963D01*
X2536798Y-789403D01*
X2536993Y-787843D01*
X2536603Y-786023D01*
X2535238Y-784723D01*
X2533873Y-784203D01*
X2532118D01*
G01X2533873D02*
X2535043Y-783423D01*
X2536018Y-782123D01*
X2536408Y-780563D01*
X2536018Y-779003D01*
X2535043Y-777703D01*
X2533288Y-776923D01*
X2531533Y-777183D01*
X2529778Y-778223D01*
G01X2514608Y1385233D02*
Y1400833D01*
X2512268Y1397713D01*
G01Y1385233D02*
X2516948D01*
G01X2528218Y1388353D02*
X2529388Y1386533D01*
X2530948Y1385493D01*
X2532703Y1385233D01*
X2534263Y1385493D01*
X2535823Y1386793D01*
X2536798Y1388353D01*
X2536993Y1389913D01*
X2536603Y1391733D01*
X2535238Y1393033D01*
X2533873Y1393553D01*
X2532118D01*
G01X2533873D02*
X2535043Y1394333D01*
X2536018Y1395633D01*
X2536408Y1397193D01*
X2536018Y1398753D01*
X2535043Y1400053D01*
X2533288Y1400833D01*
X2531533Y1400573D01*
X2529778Y1399533D01*
G01X2520810Y1381446D02*
X2851517D01*
G01X2626167Y-777373D02*
Y-796310D01*
G01X2593085Y-603015D02*
Y-693145D01*
G01X2639382Y-633712D02*
Y-613712D01*
X2636382Y-617712D01*
G01Y-633712D02*
X2642382D01*
G01X2659382Y-634379D02*
X2658882Y-634045D01*
Y-633379D01*
X2659382Y-633045D01*
X2659882Y-633379D01*
Y-634045D01*
X2659382Y-634379D01*
G01X2674632Y-625379D02*
X2676382Y-623045D01*
X2677882Y-621712D01*
X2679882Y-621046D01*
X2681632Y-621712D01*
X2682882Y-623045D01*
X2683882Y-625045D01*
X2684132Y-627379D01*
X2683882Y-629379D01*
X2682882Y-631379D01*
X2681382Y-633045D01*
X2679632Y-633712D01*
X2677632Y-633045D01*
X2675882Y-631046D01*
X2674882Y-628045D01*
X2674632Y-624712D01*
X2675132Y-620379D01*
X2675882Y-618045D01*
X2677132Y-615712D01*
X2678882Y-614045D01*
X2680632Y-613712D01*
X2682382Y-614379D01*
X2683632Y-616045D01*
G01X2691882Y-633712D02*
Y-620379D01*
G01Y-624046D02*
X2692632Y-622379D01*
X2693882Y-621046D01*
X2695632Y-620379D01*
X2697382Y-621046D01*
X2698632Y-622379D01*
X2699382Y-624046D01*
Y-633712D01*
G01Y-624046D02*
X2700132Y-622379D01*
X2701382Y-621046D01*
X2703132Y-620379D01*
X2704882Y-621046D01*
X2706132Y-622379D01*
X2706882Y-624379D01*
Y-633712D01*
G01X2711882D02*
Y-620379D01*
G01Y-624046D02*
X2712632Y-622379D01*
X2713882Y-621046D01*
X2715632Y-620379D01*
X2717382Y-621046D01*
X2718632Y-622379D01*
X2719382Y-624046D01*
Y-633712D01*
G01Y-624046D02*
X2720132Y-622379D01*
X2721382Y-621046D01*
X2723132Y-620379D01*
X2724882Y-621046D01*
X2726132Y-622379D01*
X2726882Y-624379D01*
Y-633712D01*
G01X2607818Y-665148D02*
X2609318Y-663149D01*
X2611068Y-662148D01*
X2613068Y-661815D01*
X2615568Y-662482D01*
X2617318Y-664148D01*
X2617818Y-666148D01*
X2617568Y-668149D01*
X2616568Y-669815D01*
X2611568Y-673148D01*
X2609318Y-675482D01*
X2607818Y-678816D01*
X2607318Y-681815D01*
X2617818D01*
G01X2632568Y-661815D02*
X2630568Y-662482D01*
X2629068Y-664148D01*
X2628068Y-666148D01*
X2627318Y-668815D01*
X2627068Y-671815D01*
X2627318Y-674815D01*
X2628068Y-677482D01*
X2629068Y-679482D01*
X2630568Y-681148D01*
X2632568Y-681815D01*
X2634568Y-681148D01*
X2636068Y-679482D01*
X2637068Y-677482D01*
X2637818Y-674815D01*
X2638068Y-671815D01*
X2637818Y-668815D01*
X2637068Y-666148D01*
X2636068Y-664148D01*
X2634568Y-662482D01*
X2632568Y-661815D01*
G01X2652568Y-681815D02*
Y-661815D01*
X2649568Y-665815D01*
G01Y-681815D02*
X2655568D01*
G01X2667818Y-665148D02*
X2669318Y-663149D01*
X2671068Y-662148D01*
X2673068Y-661815D01*
X2675568Y-662482D01*
X2677318Y-664148D01*
X2677818Y-666148D01*
X2677568Y-668149D01*
X2676568Y-669815D01*
X2671568Y-673148D01*
X2669318Y-675482D01*
X2667818Y-678816D01*
X2667318Y-681815D01*
X2677818D01*
G01X2689318Y-675149D02*
X2695818D01*
G01X2712568Y-681815D02*
Y-661815D01*
X2709568Y-665815D01*
G01Y-681815D02*
X2715568D01*
G01X2732568Y-661815D02*
X2730568Y-662482D01*
X2729068Y-664148D01*
X2728068Y-666148D01*
X2727318Y-668815D01*
X2727068Y-671815D01*
X2727318Y-674815D01*
X2728068Y-677482D01*
X2729068Y-679482D01*
X2730568Y-681148D01*
X2732568Y-681815D01*
X2734568Y-681148D01*
X2736068Y-679482D01*
X2737068Y-677482D01*
X2737818Y-674815D01*
X2738068Y-671815D01*
X2737818Y-668815D01*
X2737068Y-666148D01*
X2736068Y-664148D01*
X2734568Y-662482D01*
X2732568Y-661815D01*
G01X2749318Y-675149D02*
X2755818D01*
G01X2772568Y-681815D02*
Y-661815D01*
X2769568Y-665815D01*
G01Y-681815D02*
X2775568D01*
G01X2787818Y-665148D02*
X2789318Y-663149D01*
X2791068Y-662148D01*
X2793068Y-661815D01*
X2795568Y-662482D01*
X2797318Y-664148D01*
X2797818Y-666148D01*
X2797568Y-668149D01*
X2796568Y-669815D01*
X2791568Y-673148D01*
X2789318Y-675482D01*
X2787818Y-678816D01*
X2787318Y-681815D01*
X2797818D01*
G01X2626167Y1400383D02*
Y1381446D01*
G01X2734277Y-792523D02*
Y-776923D01*
X2731937Y-780043D01*
G01Y-792523D02*
X2736617D01*
G01X2754517D02*
Y-776923D01*
X2747302Y-788103D01*
X2757052D01*
G01X2734277Y1385233D02*
Y1400833D01*
X2731937Y1397713D01*
G01Y1385233D02*
X2736617D01*
G01X2754517D02*
Y1400833D01*
X2747302Y1389653D01*
X2757052D01*
G01X2784437Y-753628D02*
X2822042D01*
G01X2851519Y-632688D02*
Y-777373D01*
G01X2851517Y1381446D02*
Y-777373D01*
G01X2822042Y-753628D02*
Y-556309D01*
G01X2858960Y-671993D02*
X2859935Y-673553D01*
X2861105Y-674593D01*
X2862470Y-675113D01*
X2864030Y-674593D01*
X2865200Y-673553D01*
X2866370Y-671993D01*
X2866760Y-669913D01*
Y-659513D01*
G01X2822042Y-556309D02*
Y-497938D01*
G01X2851517Y-561491D02*
X2870454D01*
G01X2860520Y-443630D02*
X2865200D01*
G01X2862860D02*
Y-459230D01*
G01X2860520D02*
X2865200D01*
G01X2851517Y-345608D02*
X2870454D01*
G01X2858765Y-243539D02*
Y-227939D01*
G01X2866955D02*
Y-243539D01*
G01Y-235739D02*
X2858765D01*
G01X2851517Y-129727D02*
X2870454D01*
G01X2864030Y-19856D02*
X2867930D01*
Y-24536D01*
X2866760Y-26096D01*
X2865395Y-27136D01*
X2863445Y-27656D01*
X2861495Y-27136D01*
X2860130Y-26096D01*
X2858960Y-24536D01*
X2858180Y-22716D01*
X2857790Y-20636D01*
Y-18816D01*
X2858180Y-17256D01*
X2858960Y-15436D01*
X2860130Y-13876D01*
X2861300Y-12836D01*
X2862860Y-12056D01*
X2864225D01*
X2865785Y-12576D01*
X2866955Y-13616D01*
G01X2851517Y86155D02*
X2870454D01*
G01X2858775Y188415D02*
Y204015D01*
X2866185D01*
G01X2863455Y196475D02*
X2858775D01*
G01X2851517Y302037D02*
X2870454D01*
G01X2866760Y404486D02*
X2858960D01*
Y420086D01*
X2866760D01*
G01X2863640Y412546D02*
X2858960D01*
G01X2851517Y517918D02*
X2870454D01*
G01X2858570Y620179D02*
Y635779D01*
X2862470D01*
X2864030Y634999D01*
X2865200Y633959D01*
X2866175Y632399D01*
X2866955Y630579D01*
X2867150Y627979D01*
X2866955Y625379D01*
X2866175Y623559D01*
X2865200Y621999D01*
X2864030Y620959D01*
X2862470Y620179D01*
X2858570D01*
G01X2851517Y733800D02*
X2870454D01*
G01X2867150Y850550D02*
X2865980Y851330D01*
X2864615Y851850D01*
X2863055D01*
X2861300Y851070D01*
X2859935Y849770D01*
X2858960Y848210D01*
X2858180Y845610D01*
X2857985Y843270D01*
X2858375Y840930D01*
X2858960Y839370D01*
X2860130Y837810D01*
X2861495Y836770D01*
X2862860Y836250D01*
X2864225D01*
X2865590Y836770D01*
X2866760Y837550D01*
X2867735Y838590D01*
G01X2851517Y949683D02*
X2870454D01*
G01X2864420Y1060262D02*
X2865200Y1061042D01*
X2865785Y1062342D01*
X2866175Y1064162D01*
X2865785Y1065722D01*
X2865005Y1066762D01*
X2863640Y1067542D01*
X2858375D01*
Y1051942D01*
X2864810D01*
X2866175Y1052982D01*
X2866955Y1054542D01*
X2867345Y1056362D01*
X2866955Y1058182D01*
X2865785Y1059742D01*
X2864420Y1060262D01*
X2858375D01*
G01X2851328Y1165564D02*
X2870265D01*
G01X2851517Y1381446D02*
Y1286959D01*
G01X2857985Y1267824D02*
X2862860Y1283424D01*
X2867735Y1267824D01*
G01X2865980Y1273284D02*
X2859740D01*
G01X2870454Y1400383D02*
Y-796310D01*
M02*
